FILE_TYPE = MACRO_DRAWING;
SET COLOR_WIRE YELLOW;
SET COLOR_PROP MONO;
SET COLOR_DOT WHITE;
SET COLOR_ARC YELLOW;
SET COLOR_BODY GREEN;
SET COLOR_NOTE MONO;
SET PROP_DISPLAY VALUE;
SET PAGE_NUMBER P23;
FORCEADD OFFPAGE..6
(-6450 1500);
FORCEPROP 2 LAST $XR0 43 
J 0
(-6699 1500);
DISPLAY 0.638298 (-6699 1500);
PAINT MONO (-6699 1500);
FORCEPROP 2 LAST $XR1 44 
J 0
(-6789 1500);
DISPLAY 0.638298 (-6789 1500);
PAINT MONO (-6789 1500);
FORCEPROP 2 LAST CDS_LIB mstr_standard
J 0
(-6450 1500);
PAINT MONO (-6450 1500);
DISPLAY INVISIBLE (-6450 1500);
FORCEPROP 1 LAST OFFPAGE TRUE
J 0
(-6125 1375);
DISPLAY 1.170213 (-6125 1375);
PAINT GREEN (-6125 1375);
DISPLAY INVISIBLE (-6125 1375);
FORCEPROP 1 LAST COMMENT_BODY TRUE
J 0
(-6350 1425);
DISPLAY 1.170213 (-6350 1425);
PAINT GREEN (-6350 1425);
DISPLAY INVISIBLE (-6350 1425);
FORCEPROP 2 LAST PATH I1
J 0
(-6400 1575);
DISPLAY 1.021277 (-6400 1575);
PAINT ORANGE (-6400 1575);
DISPLAY INVISIBLE (-6400 1575);
FORCEADD TAP..6
(-5600 850);
FORCEPROP 3 LASTPIN (-5550 850) SIG_NAME M_A_CLK_DP<0>
J 0
(-5540 860);
DISPLAY 0.659574 (-5540 860);
PAINT MONO (-5540 860);
DISPLAY INVISIBLE (-5540 860);
FORCEPROP 1 LASTPIN (-5550 850) BN 0
J 0
(-5602 858);
DISPLAY 0.617021 (-5602 858);
PAINT PINK (-5602 858);
FORCEPROP 2 LAST CDS_LIB mstr_standard
J 0
(-5600 850);
PAINT MONO (-5600 850);
DISPLAY INVISIBLE (-5600 850);
FORCEPROP 1 LAST BODY_TYPE PLUMBING
J 0
(-5600 800);
DISPLAY 1.595745 (-5600 800);
PAINT GREEN (-5600 800);
DISPLAY INVISIBLE (-5600 800);
FORCEPROP 1 LAST HDL_TAP TRUE
J 0
(-5275 725);
DISPLAY 1.595745 (-5275 725);
PAINT GREEN (-5275 725);
DISPLAY INVISIBLE (-5275 725);
FORCEPROP 1 LAST PATH I10
J 0
(-5602 850);
DISPLAY 0.872340 (-5602 850);
PAINT GREEN (-5602 850);
DISPLAY INVISIBLE (-5602 850);
FORCEADD TAP..6
R 2
(-2875 1600);
FORCEPROP 3 LASTPIN (-2925 1600) SIG_NAME M_A_ODT<3>
J 0
(-2915 1610);
DISPLAY 0.659574 (-2915 1610);
PAINT MONO (-2915 1610);
DISPLAY INVISIBLE (-2915 1610);
FORCEPROP 1 LASTPIN (-2925 1600) BN 3
J 2
(-2873 1608);
DISPLAY 0.617021 (-2873 1608);
PAINT PINK (-2873 1608);
FORCEPROP 2 LAST CDS_LIB mstr_standard
J 0
(-2875 1600);
PAINT MONO (-2875 1600);
DISPLAY INVISIBLE (-2875 1600);
FORCEPROP 1 LAST BODY_TYPE PLUMBING
J 2
(-2875 1550);
DISPLAY 1.595745 (-2875 1550);
PAINT GREEN (-2875 1550);
DISPLAY INVISIBLE (-2875 1550);
FORCEPROP 1 LAST HDL_TAP TRUE
J 2
(-3200 1475);
DISPLAY 1.595745 (-3200 1475);
PAINT GREEN (-3200 1475);
DISPLAY INVISIBLE (-3200 1475);
FORCEPROP 1 LAST PATH I100
J 2
(-2873 1600);
DISPLAY 0.872340 (-2873 1600);
PAINT GREEN (-2873 1600);
DISPLAY INVISIBLE (-2873 1600);
FORCEADD TAP..6
R 2
(-2875 1700);
FORCEPROP 3 LASTPIN (-2925 1700) SIG_NAME M_A_CKE<0>
J 0
(-2915 1710);
DISPLAY 0.659574 (-2915 1710);
PAINT MONO (-2915 1710);
DISPLAY INVISIBLE (-2915 1710);
FORCEPROP 1 LASTPIN (-2925 1700) BN 0
J 2
(-2873 1708);
DISPLAY 0.617021 (-2873 1708);
PAINT PINK (-2873 1708);
FORCEPROP 2 LAST CDS_LIB mstr_standard
J 0
(-2875 1700);
PAINT MONO (-2875 1700);
DISPLAY INVISIBLE (-2875 1700);
FORCEPROP 1 LAST BODY_TYPE PLUMBING
J 2
(-2875 1650);
DISPLAY 1.595745 (-2875 1650);
PAINT GREEN (-2875 1650);
DISPLAY INVISIBLE (-2875 1650);
FORCEPROP 1 LAST HDL_TAP TRUE
J 2
(-3200 1575);
DISPLAY 1.595745 (-3200 1575);
PAINT GREEN (-3200 1575);
DISPLAY INVISIBLE (-3200 1575);
FORCEPROP 1 LAST PATH I101
J 2
(-2873 1700);
DISPLAY 0.872340 (-2873 1700);
PAINT GREEN (-2873 1700);
DISPLAY INVISIBLE (-2873 1700);
FORCEADD TAP..6
R 2
(-2875 1550);
FORCEPROP 3 LASTPIN (-2925 1550) SIG_NAME M_A_ODT<2>
J 0
(-2915 1560);
DISPLAY 0.659574 (-2915 1560);
PAINT MONO (-2915 1560);
DISPLAY INVISIBLE (-2915 1560);
FORCEPROP 1 LASTPIN (-2925 1550) BN 2
J 2
(-2873 1558);
DISPLAY 0.617021 (-2873 1558);
PAINT PINK (-2873 1558);
FORCEPROP 2 LAST CDS_LIB mstr_standard
J 0
(-2875 1550);
PAINT MONO (-2875 1550);
DISPLAY INVISIBLE (-2875 1550);
FORCEPROP 1 LAST BODY_TYPE PLUMBING
J 2
(-2875 1500);
DISPLAY 1.595745 (-2875 1500);
PAINT GREEN (-2875 1500);
DISPLAY INVISIBLE (-2875 1500);
FORCEPROP 1 LAST HDL_TAP TRUE
J 2
(-3200 1425);
DISPLAY 1.595745 (-3200 1425);
PAINT GREEN (-3200 1425);
DISPLAY INVISIBLE (-3200 1425);
FORCEPROP 1 LAST PATH I102
J 2
(-2873 1550);
DISPLAY 0.872340 (-2873 1550);
PAINT GREEN (-2873 1550);
DISPLAY INVISIBLE (-2873 1550);
FORCEADD TAP..6
R 2
(-2875 1500);
FORCEPROP 3 LASTPIN (-2925 1500) SIG_NAME M_A_ODT<1>
J 0
(-2915 1510);
DISPLAY 0.659574 (-2915 1510);
PAINT MONO (-2915 1510);
DISPLAY INVISIBLE (-2915 1510);
FORCEPROP 1 LASTPIN (-2925 1500) BN 1
J 2
(-2873 1508);
DISPLAY 0.617021 (-2873 1508);
PAINT PINK (-2873 1508);
FORCEPROP 2 LAST CDS_LIB mstr_standard
J 0
(-2875 1500);
PAINT MONO (-2875 1500);
DISPLAY INVISIBLE (-2875 1500);
FORCEPROP 1 LAST BODY_TYPE PLUMBING
J 2
(-2875 1450);
DISPLAY 1.595745 (-2875 1450);
PAINT GREEN (-2875 1450);
DISPLAY INVISIBLE (-2875 1450);
FORCEPROP 1 LAST HDL_TAP TRUE
J 2
(-3200 1375);
DISPLAY 1.595745 (-3200 1375);
PAINT GREEN (-3200 1375);
DISPLAY INVISIBLE (-3200 1375);
FORCEPROP 1 LAST PATH I103
J 2
(-2873 1500);
DISPLAY 0.872340 (-2873 1500);
PAINT GREEN (-2873 1500);
DISPLAY INVISIBLE (-2873 1500);
FORCEADD TAP..6
R 2
(-2875 1850);
FORCEPROP 3 LASTPIN (-2925 1850) SIG_NAME M_A_CKE<3>
J 0
(-2915 1860);
DISPLAY 0.659574 (-2915 1860);
PAINT MONO (-2915 1860);
DISPLAY INVISIBLE (-2915 1860);
FORCEPROP 1 LASTPIN (-2925 1850) BN 3
J 2
(-2873 1858);
DISPLAY 0.617021 (-2873 1858);
PAINT PINK (-2873 1858);
FORCEPROP 2 LAST CDS_LIB mstr_standard
J 0
(-2875 1850);
PAINT MONO (-2875 1850);
DISPLAY INVISIBLE (-2875 1850);
FORCEPROP 1 LAST BODY_TYPE PLUMBING
J 2
(-2875 1800);
DISPLAY 1.595745 (-2875 1800);
PAINT GREEN (-2875 1800);
DISPLAY INVISIBLE (-2875 1800);
FORCEPROP 1 LAST HDL_TAP TRUE
J 2
(-3200 1725);
DISPLAY 1.595745 (-3200 1725);
PAINT GREEN (-3200 1725);
DISPLAY INVISIBLE (-3200 1725);
FORCEPROP 1 LAST PATH I104
J 2
(-2873 1850);
DISPLAY 0.872340 (-2873 1850);
PAINT GREEN (-2873 1850);
DISPLAY INVISIBLE (-2873 1850);
FORCEADD TAP..6
R 2
(-2875 1950);
FORCEPROP 3 LASTPIN (-2925 1950) SIG_NAME M_A_MA<0>
J 0
(-2915 1960);
DISPLAY 0.659574 (-2915 1960);
PAINT MONO (-2915 1960);
DISPLAY INVISIBLE (-2915 1960);
FORCEPROP 1 LASTPIN (-2925 1950) BN 0
J 2
(-2873 1958);
DISPLAY 0.617021 (-2873 1958);
PAINT PINK (-2873 1958);
FORCEPROP 2 LAST CDS_LIB mstr_standard
J 0
(-2875 1950);
PAINT MONO (-2875 1950);
DISPLAY INVISIBLE (-2875 1950);
FORCEPROP 1 LAST BODY_TYPE PLUMBING
J 2
(-2875 1900);
DISPLAY 1.595745 (-2875 1900);
PAINT GREEN (-2875 1900);
DISPLAY INVISIBLE (-2875 1900);
FORCEPROP 1 LAST HDL_TAP TRUE
J 2
(-3200 1825);
DISPLAY 1.595745 (-3200 1825);
PAINT GREEN (-3200 1825);
DISPLAY INVISIBLE (-3200 1825);
FORCEPROP 1 LAST PATH I105
J 2
(-2873 1950);
DISPLAY 0.872340 (-2873 1950);
PAINT GREEN (-2873 1950);
DISPLAY INVISIBLE (-2873 1950);
FORCEADD TAP..6
R 2
(-2875 1800);
FORCEPROP 3 LASTPIN (-2925 1800) SIG_NAME M_A_CKE<2>
J 0
(-2915 1810);
DISPLAY 0.659574 (-2915 1810);
PAINT MONO (-2915 1810);
DISPLAY INVISIBLE (-2915 1810);
FORCEPROP 1 LASTPIN (-2925 1800) BN 2
J 2
(-2873 1808);
DISPLAY 0.617021 (-2873 1808);
PAINT PINK (-2873 1808);
FORCEPROP 2 LAST CDS_LIB mstr_standard
J 0
(-2875 1800);
PAINT MONO (-2875 1800);
DISPLAY INVISIBLE (-2875 1800);
FORCEPROP 1 LAST BODY_TYPE PLUMBING
J 2
(-2875 1750);
DISPLAY 1.595745 (-2875 1750);
PAINT GREEN (-2875 1750);
DISPLAY INVISIBLE (-2875 1750);
FORCEPROP 1 LAST HDL_TAP TRUE
J 2
(-3200 1675);
DISPLAY 1.595745 (-3200 1675);
PAINT GREEN (-3200 1675);
DISPLAY INVISIBLE (-3200 1675);
FORCEPROP 1 LAST PATH I106
J 2
(-2873 1800);
DISPLAY 0.872340 (-2873 1800);
PAINT GREEN (-2873 1800);
DISPLAY INVISIBLE (-2873 1800);
FORCEADD TAP..6
R 2
(-2875 1750);
FORCEPROP 3 LASTPIN (-2925 1750) SIG_NAME M_A_CKE<1>
J 0
(-2915 1760);
DISPLAY 0.659574 (-2915 1760);
PAINT MONO (-2915 1760);
DISPLAY INVISIBLE (-2915 1760);
FORCEPROP 1 LASTPIN (-2925 1750) BN 1
J 2
(-2873 1758);
DISPLAY 0.617021 (-2873 1758);
PAINT PINK (-2873 1758);
FORCEPROP 2 LAST CDS_LIB mstr_standard
J 0
(-2875 1750);
PAINT MONO (-2875 1750);
DISPLAY INVISIBLE (-2875 1750);
FORCEPROP 1 LAST BODY_TYPE PLUMBING
J 2
(-2875 1700);
DISPLAY 1.595745 (-2875 1700);
PAINT GREEN (-2875 1700);
DISPLAY INVISIBLE (-2875 1700);
FORCEPROP 1 LAST HDL_TAP TRUE
J 2
(-3200 1625);
DISPLAY 1.595745 (-3200 1625);
PAINT GREEN (-3200 1625);
DISPLAY INVISIBLE (-3200 1625);
FORCEPROP 1 LAST PATH I107
J 2
(-2873 1750);
DISPLAY 0.872340 (-2873 1750);
PAINT GREEN (-2873 1750);
DISPLAY INVISIBLE (-2873 1750);
FORCEADD TAP..6
R 2
(-2875 2000);
FORCEPROP 3 LASTPIN (-2925 2000) SIG_NAME M_A_MA<1>
J 0
(-2915 2010);
DISPLAY 0.659574 (-2915 2010);
PAINT MONO (-2915 2010);
DISPLAY INVISIBLE (-2915 2010);
FORCEPROP 1 LASTPIN (-2925 2000) BN 1
J 2
(-2873 2008);
DISPLAY 0.617021 (-2873 2008);
PAINT PINK (-2873 2008);
FORCEPROP 2 LAST CDS_LIB mstr_standard
J 0
(-2875 2000);
PAINT MONO (-2875 2000);
DISPLAY INVISIBLE (-2875 2000);
FORCEPROP 1 LAST BODY_TYPE PLUMBING
J 2
(-2875 1950);
DISPLAY 1.595745 (-2875 1950);
PAINT GREEN (-2875 1950);
DISPLAY INVISIBLE (-2875 1950);
FORCEPROP 1 LAST HDL_TAP TRUE
J 2
(-3200 1875);
DISPLAY 1.595745 (-3200 1875);
PAINT GREEN (-3200 1875);
DISPLAY INVISIBLE (-3200 1875);
FORCEPROP 1 LAST PATH I108
J 2
(-2873 2000);
DISPLAY 0.872340 (-2873 2000);
PAINT GREEN (-2873 2000);
DISPLAY INVISIBLE (-2873 2000);
FORCEADD TAP..6
R 2
(-2875 2050);
FORCEPROP 3 LASTPIN (-2925 2050) SIG_NAME M_A_MA<2>
J 0
(-2915 2060);
DISPLAY 0.659574 (-2915 2060);
PAINT MONO (-2915 2060);
DISPLAY INVISIBLE (-2915 2060);
FORCEPROP 1 LASTPIN (-2925 2050) BN 2
J 2
(-2873 2058);
DISPLAY 0.617021 (-2873 2058);
PAINT PINK (-2873 2058);
FORCEPROP 2 LAST CDS_LIB mstr_standard
J 0
(-2875 2050);
PAINT MONO (-2875 2050);
DISPLAY INVISIBLE (-2875 2050);
FORCEPROP 1 LAST BODY_TYPE PLUMBING
J 2
(-2875 2000);
DISPLAY 1.595745 (-2875 2000);
PAINT GREEN (-2875 2000);
DISPLAY INVISIBLE (-2875 2000);
FORCEPROP 1 LAST HDL_TAP TRUE
J 2
(-3200 1925);
DISPLAY 1.595745 (-3200 1925);
PAINT GREEN (-3200 1925);
DISPLAY INVISIBLE (-3200 1925);
FORCEPROP 1 LAST PATH I109
J 2
(-2873 2050);
DISPLAY 0.872340 (-2873 2050);
PAINT GREEN (-2873 2050);
DISPLAY INVISIBLE (-2873 2050);
FORCEADD TAP..6
(-5600 950);
FORCEPROP 3 LASTPIN (-5550 950) SIG_NAME M_A_CLK_DP<2>
J 0
(-5540 960);
DISPLAY 0.659574 (-5540 960);
PAINT MONO (-5540 960);
DISPLAY INVISIBLE (-5540 960);
FORCEPROP 1 LASTPIN (-5550 950) BN 2
J 0
(-5602 958);
DISPLAY 0.617021 (-5602 958);
PAINT PINK (-5602 958);
FORCEPROP 2 LAST CDS_LIB mstr_standard
J 0
(-5600 950);
PAINT MONO (-5600 950);
DISPLAY INVISIBLE (-5600 950);
FORCEPROP 1 LAST BODY_TYPE PLUMBING
J 0
(-5600 900);
DISPLAY 1.595745 (-5600 900);
PAINT GREEN (-5600 900);
DISPLAY INVISIBLE (-5600 900);
FORCEPROP 1 LAST HDL_TAP TRUE
J 0
(-5275 825);
DISPLAY 1.595745 (-5275 825);
PAINT GREEN (-5275 825);
DISPLAY INVISIBLE (-5275 825);
FORCEPROP 1 LAST PATH I11
J 0
(-5602 950);
DISPLAY 0.872340 (-5602 950);
PAINT GREEN (-5602 950);
DISPLAY INVISIBLE (-5602 950);
FORCEADD TAP..6
R 2
(-2875 2100);
FORCEPROP 3 LASTPIN (-2925 2100) SIG_NAME M_A_MA<3>
J 0
(-2915 2110);
DISPLAY 0.659574 (-2915 2110);
PAINT MONO (-2915 2110);
DISPLAY INVISIBLE (-2915 2110);
FORCEPROP 1 LASTPIN (-2925 2100) BN 3
J 2
(-2873 2108);
DISPLAY 0.617021 (-2873 2108);
PAINT PINK (-2873 2108);
FORCEPROP 2 LAST CDS_LIB mstr_standard
J 0
(-2875 2100);
PAINT MONO (-2875 2100);
DISPLAY INVISIBLE (-2875 2100);
FORCEPROP 1 LAST BODY_TYPE PLUMBING
J 2
(-2875 2050);
DISPLAY 1.595745 (-2875 2050);
PAINT GREEN (-2875 2050);
DISPLAY INVISIBLE (-2875 2050);
FORCEPROP 1 LAST HDL_TAP TRUE
J 2
(-3200 1975);
DISPLAY 1.595745 (-3200 1975);
PAINT GREEN (-3200 1975);
DISPLAY INVISIBLE (-3200 1975);
FORCEPROP 1 LAST PATH I110
J 2
(-2873 2100);
DISPLAY 0.872340 (-2873 2100);
PAINT GREEN (-2873 2100);
DISPLAY INVISIBLE (-2873 2100);
FORCEADD TAP..6
R 2
(-2875 2250);
FORCEPROP 3 LASTPIN (-2925 2250) SIG_NAME M_A_MA<6>
J 0
(-2915 2260);
DISPLAY 0.659574 (-2915 2260);
PAINT MONO (-2915 2260);
DISPLAY INVISIBLE (-2915 2260);
FORCEPROP 1 LASTPIN (-2925 2250) BN 6
J 2
(-2873 2258);
DISPLAY 0.617021 (-2873 2258);
PAINT PINK (-2873 2258);
FORCEPROP 2 LAST CDS_LIB mstr_standard
J 0
(-2875 2250);
PAINT MONO (-2875 2250);
DISPLAY INVISIBLE (-2875 2250);
FORCEPROP 1 LAST BODY_TYPE PLUMBING
J 2
(-2875 2200);
DISPLAY 1.595745 (-2875 2200);
PAINT GREEN (-2875 2200);
DISPLAY INVISIBLE (-2875 2200);
FORCEPROP 1 LAST HDL_TAP TRUE
J 2
(-3200 2125);
DISPLAY 1.595745 (-3200 2125);
PAINT GREEN (-3200 2125);
DISPLAY INVISIBLE (-3200 2125);
FORCEPROP 1 LAST PATH I111
J 2
(-2873 2250);
DISPLAY 0.872340 (-2873 2250);
PAINT GREEN (-2873 2250);
DISPLAY INVISIBLE (-2873 2250);
FORCEADD TAP..6
R 2
(-2875 2200);
FORCEPROP 3 LASTPIN (-2925 2200) SIG_NAME M_A_MA<5>
J 0
(-2915 2210);
DISPLAY 0.659574 (-2915 2210);
PAINT MONO (-2915 2210);
DISPLAY INVISIBLE (-2915 2210);
FORCEPROP 1 LASTPIN (-2925 2200) BN 5
J 2
(-2873 2208);
DISPLAY 0.617021 (-2873 2208);
PAINT PINK (-2873 2208);
FORCEPROP 2 LAST CDS_LIB mstr_standard
J 0
(-2875 2200);
PAINT MONO (-2875 2200);
DISPLAY INVISIBLE (-2875 2200);
FORCEPROP 1 LAST BODY_TYPE PLUMBING
J 2
(-2875 2150);
DISPLAY 1.595745 (-2875 2150);
PAINT GREEN (-2875 2150);
DISPLAY INVISIBLE (-2875 2150);
FORCEPROP 1 LAST HDL_TAP TRUE
J 2
(-3200 2075);
DISPLAY 1.595745 (-3200 2075);
PAINT GREEN (-3200 2075);
DISPLAY INVISIBLE (-3200 2075);
FORCEPROP 1 LAST PATH I112
J 2
(-2873 2200);
DISPLAY 0.872340 (-2873 2200);
PAINT GREEN (-2873 2200);
DISPLAY INVISIBLE (-2873 2200);
FORCEADD TAP..6
R 2
(-2875 2150);
FORCEPROP 3 LASTPIN (-2925 2150) SIG_NAME M_A_MA<4>
J 0
(-2915 2160);
DISPLAY 0.659574 (-2915 2160);
PAINT MONO (-2915 2160);
DISPLAY INVISIBLE (-2915 2160);
FORCEPROP 1 LASTPIN (-2925 2150) BN 4
J 2
(-2873 2158);
DISPLAY 0.617021 (-2873 2158);
PAINT PINK (-2873 2158);
FORCEPROP 2 LAST CDS_LIB mstr_standard
J 0
(-2875 2150);
PAINT MONO (-2875 2150);
DISPLAY INVISIBLE (-2875 2150);
FORCEPROP 1 LAST BODY_TYPE PLUMBING
J 2
(-2875 2100);
DISPLAY 1.595745 (-2875 2100);
PAINT GREEN (-2875 2100);
DISPLAY INVISIBLE (-2875 2100);
FORCEPROP 1 LAST HDL_TAP TRUE
J 2
(-3200 2025);
DISPLAY 1.595745 (-3200 2025);
PAINT GREEN (-3200 2025);
DISPLAY INVISIBLE (-3200 2025);
FORCEPROP 1 LAST PATH I113
J 2
(-2873 2150);
DISPLAY 0.872340 (-2873 2150);
PAINT GREEN (-2873 2150);
DISPLAY INVISIBLE (-2873 2150);
FORCEADD TAP..6
R 2
(-2875 2400);
FORCEPROP 3 LASTPIN (-2925 2400) SIG_NAME M_A_MA<9>
J 0
(-2915 2410);
DISPLAY 0.659574 (-2915 2410);
PAINT MONO (-2915 2410);
DISPLAY INVISIBLE (-2915 2410);
FORCEPROP 1 LASTPIN (-2925 2400) BN 9
J 2
(-2873 2408);
DISPLAY 0.617021 (-2873 2408);
PAINT PINK (-2873 2408);
FORCEPROP 2 LAST CDS_LIB mstr_standard
J 0
(-2875 2400);
PAINT MONO (-2875 2400);
DISPLAY INVISIBLE (-2875 2400);
FORCEPROP 1 LAST BODY_TYPE PLUMBING
J 2
(-2875 2350);
DISPLAY 1.595745 (-2875 2350);
PAINT GREEN (-2875 2350);
DISPLAY INVISIBLE (-2875 2350);
FORCEPROP 1 LAST HDL_TAP TRUE
J 2
(-3200 2275);
DISPLAY 1.595745 (-3200 2275);
PAINT GREEN (-3200 2275);
DISPLAY INVISIBLE (-3200 2275);
FORCEPROP 1 LAST PATH I114
J 2
(-2873 2400);
DISPLAY 0.872340 (-2873 2400);
PAINT GREEN (-2873 2400);
DISPLAY INVISIBLE (-2873 2400);
FORCEADD TAP..6
R 2
(-2875 2450);
FORCEPROP 3 LASTPIN (-2925 2450) SIG_NAME M_A_MA<10>
J 0
(-2915 2460);
DISPLAY 0.659574 (-2915 2460);
PAINT MONO (-2915 2460);
DISPLAY INVISIBLE (-2915 2460);
FORCEPROP 1 LASTPIN (-2925 2450) BN 10
J 2
(-2873 2458);
DISPLAY 0.617021 (-2873 2458);
PAINT PINK (-2873 2458);
FORCEPROP 2 LAST CDS_LIB mstr_standard
J 0
(-2875 2450);
PAINT MONO (-2875 2450);
DISPLAY INVISIBLE (-2875 2450);
FORCEPROP 1 LAST BODY_TYPE PLUMBING
J 2
(-2875 2400);
DISPLAY 1.595745 (-2875 2400);
PAINT GREEN (-2875 2400);
DISPLAY INVISIBLE (-2875 2400);
FORCEPROP 1 LAST HDL_TAP TRUE
J 2
(-3200 2325);
DISPLAY 1.595745 (-3200 2325);
PAINT GREEN (-3200 2325);
DISPLAY INVISIBLE (-3200 2325);
FORCEPROP 1 LAST PATH I115
J 2
(-2873 2450);
DISPLAY 0.872340 (-2873 2450);
PAINT GREEN (-2873 2450);
DISPLAY INVISIBLE (-2873 2450);
FORCEADD TAP..6
R 2
(-2875 2500);
FORCEPROP 3 LASTPIN (-2925 2500) SIG_NAME M_A_MA<11>
J 0
(-2915 2510);
DISPLAY 0.659574 (-2915 2510);
PAINT MONO (-2915 2510);
DISPLAY INVISIBLE (-2915 2510);
FORCEPROP 1 LASTPIN (-2925 2500) BN 11
J 2
(-2873 2508);
DISPLAY 0.617021 (-2873 2508);
PAINT PINK (-2873 2508);
FORCEPROP 2 LAST CDS_LIB mstr_standard
J 0
(-2875 2500);
PAINT MONO (-2875 2500);
DISPLAY INVISIBLE (-2875 2500);
FORCEPROP 1 LAST BODY_TYPE PLUMBING
J 2
(-2875 2450);
DISPLAY 1.595745 (-2875 2450);
PAINT GREEN (-2875 2450);
DISPLAY INVISIBLE (-2875 2450);
FORCEPROP 1 LAST HDL_TAP TRUE
J 2
(-3200 2375);
DISPLAY 1.595745 (-3200 2375);
PAINT GREEN (-3200 2375);
DISPLAY INVISIBLE (-3200 2375);
FORCEPROP 1 LAST PATH I116
J 2
(-2873 2500);
DISPLAY 0.872340 (-2873 2500);
PAINT GREEN (-2873 2500);
DISPLAY INVISIBLE (-2873 2500);
FORCEADD TAP..6
R 2
(-2875 2350);
FORCEPROP 3 LASTPIN (-2925 2350) SIG_NAME M_A_MA<8>
J 0
(-2915 2360);
DISPLAY 0.659574 (-2915 2360);
PAINT MONO (-2915 2360);
DISPLAY INVISIBLE (-2915 2360);
FORCEPROP 1 LASTPIN (-2925 2350) BN 8
J 2
(-2873 2358);
DISPLAY 0.617021 (-2873 2358);
PAINT PINK (-2873 2358);
FORCEPROP 2 LAST CDS_LIB mstr_standard
J 0
(-2875 2350);
PAINT MONO (-2875 2350);
DISPLAY INVISIBLE (-2875 2350);
FORCEPROP 1 LAST BODY_TYPE PLUMBING
J 2
(-2875 2300);
DISPLAY 1.595745 (-2875 2300);
PAINT GREEN (-2875 2300);
DISPLAY INVISIBLE (-2875 2300);
FORCEPROP 1 LAST HDL_TAP TRUE
J 2
(-3200 2225);
DISPLAY 1.595745 (-3200 2225);
PAINT GREEN (-3200 2225);
DISPLAY INVISIBLE (-3200 2225);
FORCEPROP 1 LAST PATH I117
J 2
(-2873 2350);
DISPLAY 0.872340 (-2873 2350);
PAINT GREEN (-2873 2350);
DISPLAY INVISIBLE (-2873 2350);
FORCEADD TAP..6
R 2
(-2875 2300);
FORCEPROP 3 LASTPIN (-2925 2300) SIG_NAME M_A_MA<7>
J 0
(-2915 2310);
DISPLAY 0.659574 (-2915 2310);
PAINT MONO (-2915 2310);
DISPLAY INVISIBLE (-2915 2310);
FORCEPROP 1 LASTPIN (-2925 2300) BN 7
J 2
(-2873 2308);
DISPLAY 0.617021 (-2873 2308);
PAINT PINK (-2873 2308);
FORCEPROP 2 LAST CDS_LIB mstr_standard
J 0
(-2875 2300);
PAINT MONO (-2875 2300);
DISPLAY INVISIBLE (-2875 2300);
FORCEPROP 1 LAST BODY_TYPE PLUMBING
J 2
(-2875 2250);
DISPLAY 1.595745 (-2875 2250);
PAINT GREEN (-2875 2250);
DISPLAY INVISIBLE (-2875 2250);
FORCEPROP 1 LAST HDL_TAP TRUE
J 2
(-3200 2175);
DISPLAY 1.595745 (-3200 2175);
PAINT GREEN (-3200 2175);
DISPLAY INVISIBLE (-3200 2175);
FORCEPROP 1 LAST PATH I118
J 2
(-2873 2300);
DISPLAY 0.872340 (-2873 2300);
PAINT GREEN (-2873 2300);
DISPLAY INVISIBLE (-2873 2300);
FORCEADD TAP..6
R 2
(-2875 2650);
FORCEPROP 3 LASTPIN (-2925 2650) SIG_NAME M_A_MA<14>
J 0
(-2915 2660);
DISPLAY 0.659574 (-2915 2660);
PAINT MONO (-2915 2660);
DISPLAY INVISIBLE (-2915 2660);
FORCEPROP 1 LASTPIN (-2925 2650) BN 14
J 2
(-2873 2658);
DISPLAY 0.617021 (-2873 2658);
PAINT PINK (-2873 2658);
FORCEPROP 2 LAST CDS_LIB mstr_standard
J 0
(-2875 2650);
PAINT MONO (-2875 2650);
DISPLAY INVISIBLE (-2875 2650);
FORCEPROP 1 LAST BODY_TYPE PLUMBING
J 2
(-2875 2600);
DISPLAY 1.595745 (-2875 2600);
PAINT GREEN (-2875 2600);
DISPLAY INVISIBLE (-2875 2600);
FORCEPROP 1 LAST HDL_TAP TRUE
J 2
(-3200 2525);
DISPLAY 1.595745 (-3200 2525);
PAINT GREEN (-3200 2525);
DISPLAY INVISIBLE (-3200 2525);
FORCEPROP 1 LAST PATH I119
J 2
(-2873 2650);
DISPLAY 0.872340 (-2873 2650);
PAINT GREEN (-2873 2650);
DISPLAY INVISIBLE (-2873 2650);
FORCEADD TAP..6
(-5600 1000);
FORCEPROP 3 LASTPIN (-5550 1000) SIG_NAME M_A_CLK_DP<3>
J 0
(-5540 1010);
DISPLAY 0.659574 (-5540 1010);
PAINT MONO (-5540 1010);
DISPLAY INVISIBLE (-5540 1010);
FORCEPROP 1 LASTPIN (-5550 1000) BN 3
J 0
(-5602 1008);
DISPLAY 0.617021 (-5602 1008);
PAINT PINK (-5602 1008);
FORCEPROP 2 LAST CDS_LIB mstr_standard
J 0
(-5600 1000);
PAINT MONO (-5600 1000);
DISPLAY INVISIBLE (-5600 1000);
FORCEPROP 1 LAST BODY_TYPE PLUMBING
J 0
(-5600 950);
DISPLAY 1.595745 (-5600 950);
PAINT GREEN (-5600 950);
DISPLAY INVISIBLE (-5600 950);
FORCEPROP 1 LAST HDL_TAP TRUE
J 0
(-5275 875);
DISPLAY 1.595745 (-5275 875);
PAINT GREEN (-5275 875);
DISPLAY INVISIBLE (-5275 875);
FORCEPROP 1 LAST PATH I12
J 0
(-5602 1000);
DISPLAY 0.872340 (-5602 1000);
PAINT GREEN (-5602 1000);
DISPLAY INVISIBLE (-5602 1000);
FORCEADD TAP..6
R 2
(-2875 2700);
FORCEPROP 3 LASTPIN (-2925 2700) SIG_NAME M_A_MA<15>
J 0
(-2915 2710);
DISPLAY 0.659574 (-2915 2710);
PAINT MONO (-2915 2710);
DISPLAY INVISIBLE (-2915 2710);
FORCEPROP 1 LASTPIN (-2925 2700) BN 15
J 2
(-2873 2708);
DISPLAY 0.617021 (-2873 2708);
PAINT PINK (-2873 2708);
FORCEPROP 2 LAST CDS_LIB mstr_standard
J 0
(-2875 2700);
PAINT MONO (-2875 2700);
DISPLAY INVISIBLE (-2875 2700);
FORCEPROP 1 LAST BODY_TYPE PLUMBING
J 2
(-2875 2650);
DISPLAY 1.595745 (-2875 2650);
PAINT GREEN (-2875 2650);
DISPLAY INVISIBLE (-2875 2650);
FORCEPROP 1 LAST HDL_TAP TRUE
J 2
(-3200 2575);
DISPLAY 1.595745 (-3200 2575);
PAINT GREEN (-3200 2575);
DISPLAY INVISIBLE (-3200 2575);
FORCEPROP 1 LAST PATH I120
J 2
(-2873 2700);
DISPLAY 0.872340 (-2873 2700);
PAINT GREEN (-2873 2700);
DISPLAY INVISIBLE (-2873 2700);
FORCEADD TAP..6
R 2
(-2875 2750);
FORCEPROP 3 LASTPIN (-2925 2750) SIG_NAME M_A_MA<16>
J 0
(-2915 2760);
DISPLAY 0.659574 (-2915 2760);
PAINT MONO (-2915 2760);
DISPLAY INVISIBLE (-2915 2760);
FORCEPROP 1 LASTPIN (-2925 2750) BN 16
J 2
(-2873 2758);
DISPLAY 0.617021 (-2873 2758);
PAINT PINK (-2873 2758);
FORCEPROP 2 LAST CDS_LIB mstr_standard
J 0
(-2875 2750);
PAINT MONO (-2875 2750);
DISPLAY INVISIBLE (-2875 2750);
FORCEPROP 1 LAST BODY_TYPE PLUMBING
J 2
(-2875 2700);
DISPLAY 1.595745 (-2875 2700);
PAINT GREEN (-2875 2700);
DISPLAY INVISIBLE (-2875 2700);
FORCEPROP 1 LAST HDL_TAP TRUE
J 2
(-3200 2625);
DISPLAY 1.595745 (-3200 2625);
PAINT GREEN (-3200 2625);
DISPLAY INVISIBLE (-3200 2625);
FORCEPROP 1 LAST PATH I121
J 2
(-2873 2750);
DISPLAY 0.872340 (-2873 2750);
PAINT GREEN (-2873 2750);
DISPLAY INVISIBLE (-2873 2750);
FORCEADD TAP..6
R 2
(-2875 2600);
FORCEPROP 3 LASTPIN (-2925 2600) SIG_NAME M_A_MA<13>
J 0
(-2915 2610);
DISPLAY 0.659574 (-2915 2610);
PAINT MONO (-2915 2610);
DISPLAY INVISIBLE (-2915 2610);
FORCEPROP 1 LASTPIN (-2925 2600) BN 13
J 2
(-2873 2608);
DISPLAY 0.617021 (-2873 2608);
PAINT PINK (-2873 2608);
FORCEPROP 2 LAST CDS_LIB mstr_standard
J 0
(-2875 2600);
PAINT MONO (-2875 2600);
DISPLAY INVISIBLE (-2875 2600);
FORCEPROP 1 LAST BODY_TYPE PLUMBING
J 2
(-2875 2550);
DISPLAY 1.595745 (-2875 2550);
PAINT GREEN (-2875 2550);
DISPLAY INVISIBLE (-2875 2550);
FORCEPROP 1 LAST HDL_TAP TRUE
J 2
(-3200 2475);
DISPLAY 1.595745 (-3200 2475);
PAINT GREEN (-3200 2475);
DISPLAY INVISIBLE (-3200 2475);
FORCEPROP 1 LAST PATH I122
J 2
(-2873 2600);
DISPLAY 0.872340 (-2873 2600);
PAINT GREEN (-2873 2600);
DISPLAY INVISIBLE (-2873 2600);
FORCEADD TAP..6
R 2
(-2875 2550);
FORCEPROP 3 LASTPIN (-2925 2550) SIG_NAME M_A_MA<12>
J 0
(-2915 2560);
DISPLAY 0.659574 (-2915 2560);
PAINT MONO (-2915 2560);
DISPLAY INVISIBLE (-2915 2560);
FORCEPROP 1 LASTPIN (-2925 2550) BN 12
J 2
(-2873 2558);
DISPLAY 0.617021 (-2873 2558);
PAINT PINK (-2873 2558);
FORCEPROP 2 LAST CDS_LIB mstr_standard
J 0
(-2875 2550);
PAINT MONO (-2875 2550);
DISPLAY INVISIBLE (-2875 2550);
FORCEPROP 1 LAST BODY_TYPE PLUMBING
J 2
(-2875 2500);
DISPLAY 1.595745 (-2875 2500);
PAINT GREEN (-2875 2500);
DISPLAY INVISIBLE (-2875 2500);
FORCEPROP 1 LAST HDL_TAP TRUE
J 2
(-3200 2425);
DISPLAY 1.595745 (-3200 2425);
PAINT GREEN (-3200 2425);
DISPLAY INVISIBLE (-3200 2425);
FORCEPROP 1 LAST PATH I123
J 2
(-2873 2550);
DISPLAY 0.872340 (-2873 2550);
PAINT GREEN (-2873 2550);
DISPLAY INVISIBLE (-2873 2550);
FORCEADD TAP..6
R 2
(-2875 2900);
FORCEPROP 3 LASTPIN (-2925 2900) SIG_NAME M_A_DQS_DN<0>
J 0
(-2915 2910);
DISPLAY 0.659574 (-2915 2910);
PAINT MONO (-2915 2910);
DISPLAY INVISIBLE (-2915 2910);
FORCEPROP 1 LASTPIN (-2925 2900) BN 0
J 2
(-2873 2908);
DISPLAY 0.617021 (-2873 2908);
PAINT PINK (-2873 2908);
FORCEPROP 2 LAST CDS_LIB mstr_standard
J 0
(-2875 2900);
PAINT MONO (-2875 2900);
DISPLAY INVISIBLE (-2875 2900);
FORCEPROP 1 LAST BODY_TYPE PLUMBING
J 2
(-2875 2850);
DISPLAY 1.595745 (-2875 2850);
PAINT GREEN (-2875 2850);
DISPLAY INVISIBLE (-2875 2850);
FORCEPROP 1 LAST HDL_TAP TRUE
J 2
(-3200 2775);
DISPLAY 1.595745 (-3200 2775);
PAINT GREEN (-3200 2775);
DISPLAY INVISIBLE (-3200 2775);
FORCEPROP 1 LAST PATH I124
J 2
(-2873 2900);
DISPLAY 0.872340 (-2873 2900);
PAINT GREEN (-2873 2900);
DISPLAY INVISIBLE (-2873 2900);
FORCEADD TAP..6
R 2
(-2875 3000);
FORCEPROP 3 LASTPIN (-2925 3000) SIG_NAME M_A_DQS_DN<2>
J 0
(-2915 3010);
DISPLAY 0.659574 (-2915 3010);
PAINT MONO (-2915 3010);
DISPLAY INVISIBLE (-2915 3010);
FORCEPROP 1 LASTPIN (-2925 3000) BN 2
J 2
(-2873 3008);
DISPLAY 0.617021 (-2873 3008);
PAINT PINK (-2873 3008);
FORCEPROP 2 LAST CDS_LIB mstr_standard
J 0
(-2875 3000);
PAINT MONO (-2875 3000);
DISPLAY INVISIBLE (-2875 3000);
FORCEPROP 1 LAST BODY_TYPE PLUMBING
J 2
(-2875 2950);
DISPLAY 1.595745 (-2875 2950);
PAINT GREEN (-2875 2950);
DISPLAY INVISIBLE (-2875 2950);
FORCEPROP 1 LAST HDL_TAP TRUE
J 2
(-3200 2875);
DISPLAY 1.595745 (-3200 2875);
PAINT GREEN (-3200 2875);
DISPLAY INVISIBLE (-3200 2875);
FORCEPROP 1 LAST PATH I125
J 2
(-2873 3000);
DISPLAY 0.872340 (-2873 3000);
PAINT GREEN (-2873 3000);
DISPLAY INVISIBLE (-2873 3000);
FORCEADD TAP..6
R 2
(-2875 2950);
FORCEPROP 3 LASTPIN (-2925 2950) SIG_NAME M_A_DQS_DN<1>
J 0
(-2915 2960);
DISPLAY 0.659574 (-2915 2960);
PAINT MONO (-2915 2960);
DISPLAY INVISIBLE (-2915 2960);
FORCEPROP 1 LASTPIN (-2925 2950) BN 1
J 2
(-2873 2958);
DISPLAY 0.617021 (-2873 2958);
PAINT PINK (-2873 2958);
FORCEPROP 2 LAST CDS_LIB mstr_standard
J 0
(-2875 2950);
PAINT MONO (-2875 2950);
DISPLAY INVISIBLE (-2875 2950);
FORCEPROP 1 LAST BODY_TYPE PLUMBING
J 2
(-2875 2900);
DISPLAY 1.595745 (-2875 2900);
PAINT GREEN (-2875 2900);
DISPLAY INVISIBLE (-2875 2900);
FORCEPROP 1 LAST HDL_TAP TRUE
J 2
(-3200 2825);
DISPLAY 1.595745 (-3200 2825);
PAINT GREEN (-3200 2825);
DISPLAY INVISIBLE (-3200 2825);
FORCEPROP 1 LAST PATH I126
J 2
(-2873 2950);
DISPLAY 0.872340 (-2873 2950);
PAINT GREEN (-2873 2950);
DISPLAY INVISIBLE (-2873 2950);
FORCEADD TAP..6
R 2
(-2875 2800);
FORCEPROP 3 LASTPIN (-2925 2800) SIG_NAME M_A_MA<17>
J 0
(-2915 2810);
DISPLAY 0.659574 (-2915 2810);
PAINT MONO (-2915 2810);
DISPLAY INVISIBLE (-2915 2810);
FORCEPROP 1 LASTPIN (-2925 2800) BN 17
J 2
(-2873 2808);
DISPLAY 0.617021 (-2873 2808);
PAINT PINK (-2873 2808);
FORCEPROP 2 LAST CDS_LIB mstr_standard
J 0
(-2875 2800);
PAINT MONO (-2875 2800);
DISPLAY INVISIBLE (-2875 2800);
FORCEPROP 1 LAST BODY_TYPE PLUMBING
J 2
(-2875 2750);
DISPLAY 1.595745 (-2875 2750);
PAINT GREEN (-2875 2750);
DISPLAY INVISIBLE (-2875 2750);
FORCEPROP 1 LAST HDL_TAP TRUE
J 2
(-3200 2675);
DISPLAY 1.595745 (-3200 2675);
PAINT GREEN (-3200 2675);
DISPLAY INVISIBLE (-3200 2675);
FORCEPROP 1 LAST PATH I127
J 2
(-2873 2800);
DISPLAY 0.872340 (-2873 2800);
PAINT GREEN (-2873 2800);
DISPLAY INVISIBLE (-2873 2800);
FORCEADD TAP..6
R 2
(-2875 3200);
FORCEPROP 3 LASTPIN (-2925 3200) SIG_NAME M_A_DQS_DN<6>
J 0
(-2915 3210);
DISPLAY 0.659574 (-2915 3210);
PAINT MONO (-2915 3210);
DISPLAY INVISIBLE (-2915 3210);
FORCEPROP 1 LASTPIN (-2925 3200) BN 6
J 2
(-2873 3208);
DISPLAY 0.617021 (-2873 3208);
PAINT PINK (-2873 3208);
FORCEPROP 2 LAST CDS_LIB mstr_standard
J 0
(-2875 3200);
PAINT MONO (-2875 3200);
DISPLAY INVISIBLE (-2875 3200);
FORCEPROP 1 LAST BODY_TYPE PLUMBING
J 2
(-2875 3150);
DISPLAY 1.595745 (-2875 3150);
PAINT GREEN (-2875 3150);
DISPLAY INVISIBLE (-2875 3150);
FORCEPROP 1 LAST HDL_TAP TRUE
J 2
(-3200 3075);
DISPLAY 1.595745 (-3200 3075);
PAINT GREEN (-3200 3075);
DISPLAY INVISIBLE (-3200 3075);
FORCEPROP 1 LAST PATH I128
J 2
(-2873 3200);
DISPLAY 0.872340 (-2873 3200);
PAINT GREEN (-2873 3200);
DISPLAY INVISIBLE (-2873 3200);
FORCEADD TAP..6
R 2
(-2875 3250);
FORCEPROP 3 LASTPIN (-2925 3250) SIG_NAME M_A_DQS_DN<7>
J 0
(-2915 3260);
DISPLAY 0.659574 (-2915 3260);
PAINT MONO (-2915 3260);
DISPLAY INVISIBLE (-2915 3260);
FORCEPROP 1 LASTPIN (-2925 3250) BN 7
J 2
(-2873 3258);
DISPLAY 0.617021 (-2873 3258);
PAINT PINK (-2873 3258);
FORCEPROP 2 LAST CDS_LIB mstr_standard
J 0
(-2875 3250);
PAINT MONO (-2875 3250);
DISPLAY INVISIBLE (-2875 3250);
FORCEPROP 1 LAST BODY_TYPE PLUMBING
J 2
(-2875 3200);
DISPLAY 1.595745 (-2875 3200);
PAINT GREEN (-2875 3200);
DISPLAY INVISIBLE (-2875 3200);
FORCEPROP 1 LAST HDL_TAP TRUE
J 2
(-3200 3125);
DISPLAY 1.595745 (-3200 3125);
PAINT GREEN (-3200 3125);
DISPLAY INVISIBLE (-3200 3125);
FORCEPROP 1 LAST PATH I129
J 2
(-2873 3250);
DISPLAY 0.872340 (-2873 3250);
PAINT GREEN (-2873 3250);
DISPLAY INVISIBLE (-2873 3250);
FORCEADD TAP..6
(-5600 1100);
FORCEPROP 3 LASTPIN (-5550 1100) SIG_NAME M_A_ECC<0>
J 0
(-5540 1110);
DISPLAY 0.659574 (-5540 1110);
PAINT MONO (-5540 1110);
DISPLAY INVISIBLE (-5540 1110);
FORCEPROP 1 LASTPIN (-5550 1100) BN 0
J 0
(-5602 1108);
DISPLAY 0.617021 (-5602 1108);
PAINT PINK (-5602 1108);
FORCEPROP 2 LAST CDS_LIB mstr_standard
J 0
(-5600 1100);
PAINT MONO (-5600 1100);
DISPLAY INVISIBLE (-5600 1100);
FORCEPROP 1 LAST BODY_TYPE PLUMBING
J 0
(-5600 1050);
DISPLAY 1.595745 (-5600 1050);
PAINT GREEN (-5600 1050);
DISPLAY INVISIBLE (-5600 1050);
FORCEPROP 1 LAST HDL_TAP TRUE
J 0
(-5275 975);
DISPLAY 1.595745 (-5275 975);
PAINT GREEN (-5275 975);
DISPLAY INVISIBLE (-5275 975);
FORCEPROP 1 LAST PATH I13
J 0
(-5602 1100);
DISPLAY 0.872340 (-5602 1100);
PAINT GREEN (-5602 1100);
DISPLAY INVISIBLE (-5602 1100);
FORCEADD TAP..6
R 2
(-2875 3150);
FORCEPROP 3 LASTPIN (-2925 3150) SIG_NAME M_A_DQS_DN<5>
J 0
(-2915 3160);
DISPLAY 0.659574 (-2915 3160);
PAINT MONO (-2915 3160);
DISPLAY INVISIBLE (-2915 3160);
FORCEPROP 1 LASTPIN (-2925 3150) BN 5
J 2
(-2873 3158);
DISPLAY 0.617021 (-2873 3158);
PAINT PINK (-2873 3158);
FORCEPROP 2 LAST CDS_LIB mstr_standard
J 0
(-2875 3150);
PAINT MONO (-2875 3150);
DISPLAY INVISIBLE (-2875 3150);
FORCEPROP 1 LAST BODY_TYPE PLUMBING
J 2
(-2875 3100);
DISPLAY 1.595745 (-2875 3100);
PAINT GREEN (-2875 3100);
DISPLAY INVISIBLE (-2875 3100);
FORCEPROP 1 LAST HDL_TAP TRUE
J 2
(-3200 3025);
DISPLAY 1.595745 (-3200 3025);
PAINT GREEN (-3200 3025);
DISPLAY INVISIBLE (-3200 3025);
FORCEPROP 1 LAST PATH I130
J 2
(-2873 3150);
DISPLAY 0.872340 (-2873 3150);
PAINT GREEN (-2873 3150);
DISPLAY INVISIBLE (-2873 3150);
FORCEADD TAP..6
R 2
(-2875 3100);
FORCEPROP 3 LASTPIN (-2925 3100) SIG_NAME M_A_DQS_DN<4>
J 0
(-2915 3110);
DISPLAY 0.659574 (-2915 3110);
PAINT MONO (-2915 3110);
DISPLAY INVISIBLE (-2915 3110);
FORCEPROP 1 LASTPIN (-2925 3100) BN 4
J 2
(-2873 3108);
DISPLAY 0.617021 (-2873 3108);
PAINT PINK (-2873 3108);
FORCEPROP 2 LAST CDS_LIB mstr_standard
J 0
(-2875 3100);
PAINT MONO (-2875 3100);
DISPLAY INVISIBLE (-2875 3100);
FORCEPROP 1 LAST BODY_TYPE PLUMBING
J 2
(-2875 3050);
DISPLAY 1.595745 (-2875 3050);
PAINT GREEN (-2875 3050);
DISPLAY INVISIBLE (-2875 3050);
FORCEPROP 1 LAST HDL_TAP TRUE
J 2
(-3200 2975);
DISPLAY 1.595745 (-3200 2975);
PAINT GREEN (-3200 2975);
DISPLAY INVISIBLE (-3200 2975);
FORCEPROP 1 LAST PATH I131
J 2
(-2873 3100);
DISPLAY 0.872340 (-2873 3100);
PAINT GREEN (-2873 3100);
DISPLAY INVISIBLE (-2873 3100);
FORCEADD TAP..6
R 2
(-2875 3050);
FORCEPROP 3 LASTPIN (-2925 3050) SIG_NAME M_A_DQS_DN<3>
J 0
(-2915 3060);
DISPLAY 0.659574 (-2915 3060);
PAINT MONO (-2915 3060);
DISPLAY INVISIBLE (-2915 3060);
FORCEPROP 1 LASTPIN (-2925 3050) BN 3
J 2
(-2873 3058);
DISPLAY 0.617021 (-2873 3058);
PAINT PINK (-2873 3058);
FORCEPROP 2 LAST CDS_LIB mstr_standard
J 0
(-2875 3050);
PAINT MONO (-2875 3050);
DISPLAY INVISIBLE (-2875 3050);
FORCEPROP 1 LAST BODY_TYPE PLUMBING
J 2
(-2875 3000);
DISPLAY 1.595745 (-2875 3000);
PAINT GREEN (-2875 3000);
DISPLAY INVISIBLE (-2875 3000);
FORCEPROP 1 LAST HDL_TAP TRUE
J 2
(-3200 2925);
DISPLAY 1.595745 (-3200 2925);
PAINT GREEN (-3200 2925);
DISPLAY INVISIBLE (-3200 2925);
FORCEPROP 1 LAST PATH I132
J 2
(-2873 3050);
DISPLAY 0.872340 (-2873 3050);
PAINT GREEN (-2873 3050);
DISPLAY INVISIBLE (-2873 3050);
FORCEADD TAP..6
R 2
(-2875 3500);
FORCEPROP 3 LASTPIN (-2925 3500) SIG_NAME M_A_DQS_DN<12>
J 0
(-2915 3510);
DISPLAY 0.659574 (-2915 3510);
PAINT MONO (-2915 3510);
DISPLAY INVISIBLE (-2915 3510);
FORCEPROP 1 LASTPIN (-2925 3500) BN 12
J 2
(-2873 3508);
DISPLAY 0.617021 (-2873 3508);
PAINT PINK (-2873 3508);
FORCEPROP 2 LAST CDS_LIB mstr_standard
J 0
(-2875 3500);
PAINT MONO (-2875 3500);
DISPLAY INVISIBLE (-2875 3500);
FORCEPROP 1 LAST BODY_TYPE PLUMBING
J 2
(-2875 3450);
DISPLAY 1.595745 (-2875 3450);
PAINT GREEN (-2875 3450);
DISPLAY INVISIBLE (-2875 3450);
FORCEPROP 1 LAST HDL_TAP TRUE
J 2
(-3200 3375);
DISPLAY 1.595745 (-3200 3375);
PAINT GREEN (-3200 3375);
DISPLAY INVISIBLE (-3200 3375);
FORCEPROP 1 LAST PATH I133
J 2
(-2873 3500);
DISPLAY 0.872340 (-2873 3500);
PAINT GREEN (-2873 3500);
DISPLAY INVISIBLE (-2873 3500);
FORCEADD TAP..6
R 2
(-2875 3450);
FORCEPROP 3 LASTPIN (-2925 3450) SIG_NAME M_A_DQS_DN<11>
J 0
(-2915 3460);
DISPLAY 0.659574 (-2915 3460);
PAINT MONO (-2915 3460);
DISPLAY INVISIBLE (-2915 3460);
FORCEPROP 1 LASTPIN (-2925 3450) BN 11
J 2
(-2873 3458);
DISPLAY 0.617021 (-2873 3458);
PAINT PINK (-2873 3458);
FORCEPROP 2 LAST CDS_LIB mstr_standard
J 0
(-2875 3450);
PAINT MONO (-2875 3450);
DISPLAY INVISIBLE (-2875 3450);
FORCEPROP 1 LAST BODY_TYPE PLUMBING
J 2
(-2875 3400);
DISPLAY 1.595745 (-2875 3400);
PAINT GREEN (-2875 3400);
DISPLAY INVISIBLE (-2875 3400);
FORCEPROP 1 LAST HDL_TAP TRUE
J 2
(-3200 3325);
DISPLAY 1.595745 (-3200 3325);
PAINT GREEN (-3200 3325);
DISPLAY INVISIBLE (-3200 3325);
FORCEPROP 1 LAST PATH I134
J 2
(-2873 3450);
DISPLAY 0.872340 (-2873 3450);
PAINT GREEN (-2873 3450);
DISPLAY INVISIBLE (-2873 3450);
FORCEADD TAP..6
R 2
(-2875 3400);
FORCEPROP 3 LASTPIN (-2925 3400) SIG_NAME M_A_DQS_DN<10>
J 0
(-2915 3410);
DISPLAY 0.659574 (-2915 3410);
PAINT MONO (-2915 3410);
DISPLAY INVISIBLE (-2915 3410);
FORCEPROP 1 LASTPIN (-2925 3400) BN 10
J 2
(-2873 3408);
DISPLAY 0.617021 (-2873 3408);
PAINT PINK (-2873 3408);
FORCEPROP 2 LAST CDS_LIB mstr_standard
J 0
(-2875 3400);
PAINT MONO (-2875 3400);
DISPLAY INVISIBLE (-2875 3400);
FORCEPROP 1 LAST BODY_TYPE PLUMBING
J 2
(-2875 3350);
DISPLAY 1.595745 (-2875 3350);
PAINT GREEN (-2875 3350);
DISPLAY INVISIBLE (-2875 3350);
FORCEPROP 1 LAST HDL_TAP TRUE
J 2
(-3200 3275);
DISPLAY 1.595745 (-3200 3275);
PAINT GREEN (-3200 3275);
DISPLAY INVISIBLE (-3200 3275);
FORCEPROP 1 LAST PATH I135
J 2
(-2873 3400);
DISPLAY 0.872340 (-2873 3400);
PAINT GREEN (-2873 3400);
DISPLAY INVISIBLE (-2873 3400);
FORCEADD TAP..6
R 2
(-2875 3350);
FORCEPROP 3 LASTPIN (-2925 3350) SIG_NAME M_A_DQS_DN<9>
J 0
(-2915 3360);
DISPLAY 0.659574 (-2915 3360);
PAINT MONO (-2915 3360);
DISPLAY INVISIBLE (-2915 3360);
FORCEPROP 1 LASTPIN (-2925 3350) BN 9
J 2
(-2873 3358);
DISPLAY 0.617021 (-2873 3358);
PAINT PINK (-2873 3358);
FORCEPROP 2 LAST CDS_LIB mstr_standard
J 0
(-2875 3350);
PAINT MONO (-2875 3350);
DISPLAY INVISIBLE (-2875 3350);
FORCEPROP 1 LAST BODY_TYPE PLUMBING
J 2
(-2875 3300);
DISPLAY 1.595745 (-2875 3300);
PAINT GREEN (-2875 3300);
DISPLAY INVISIBLE (-2875 3300);
FORCEPROP 1 LAST HDL_TAP TRUE
J 2
(-3200 3225);
DISPLAY 1.595745 (-3200 3225);
PAINT GREEN (-3200 3225);
DISPLAY INVISIBLE (-3200 3225);
FORCEPROP 1 LAST PATH I136
J 2
(-2873 3350);
DISPLAY 0.872340 (-2873 3350);
PAINT GREEN (-2873 3350);
DISPLAY INVISIBLE (-2873 3350);
FORCEADD TAP..6
R 2
(-2875 3300);
FORCEPROP 3 LASTPIN (-2925 3300) SIG_NAME M_A_DQS_DN<8>
J 0
(-2915 3310);
DISPLAY 0.659574 (-2915 3310);
PAINT MONO (-2915 3310);
DISPLAY INVISIBLE (-2915 3310);
FORCEPROP 1 LASTPIN (-2925 3300) BN 8
J 2
(-2873 3308);
DISPLAY 0.617021 (-2873 3308);
PAINT PINK (-2873 3308);
FORCEPROP 2 LAST CDS_LIB mstr_standard
J 0
(-2875 3300);
PAINT MONO (-2875 3300);
DISPLAY INVISIBLE (-2875 3300);
FORCEPROP 1 LAST BODY_TYPE PLUMBING
J 2
(-2875 3250);
DISPLAY 1.595745 (-2875 3250);
PAINT GREEN (-2875 3250);
DISPLAY INVISIBLE (-2875 3250);
FORCEPROP 1 LAST HDL_TAP TRUE
J 2
(-3200 3175);
DISPLAY 1.595745 (-3200 3175);
PAINT GREEN (-3200 3175);
DISPLAY INVISIBLE (-3200 3175);
FORCEPROP 1 LAST PATH I137
J 2
(-2873 3300);
DISPLAY 0.872340 (-2873 3300);
PAINT GREEN (-2873 3300);
DISPLAY INVISIBLE (-2873 3300);
FORCEADD TAP..6
R 2
(-2875 3700);
FORCEPROP 3 LASTPIN (-2925 3700) SIG_NAME M_A_DQS_DN<16>
J 0
(-2915 3710);
DISPLAY 0.659574 (-2915 3710);
PAINT MONO (-2915 3710);
DISPLAY INVISIBLE (-2915 3710);
FORCEPROP 1 LASTPIN (-2925 3700) BN 16
J 2
(-2873 3708);
DISPLAY 0.617021 (-2873 3708);
PAINT PINK (-2873 3708);
FORCEPROP 2 LAST CDS_LIB mstr_standard
J 0
(-2875 3700);
PAINT MONO (-2875 3700);
DISPLAY INVISIBLE (-2875 3700);
FORCEPROP 1 LAST BODY_TYPE PLUMBING
J 2
(-2875 3650);
DISPLAY 1.595745 (-2875 3650);
PAINT GREEN (-2875 3650);
DISPLAY INVISIBLE (-2875 3650);
FORCEPROP 1 LAST HDL_TAP TRUE
J 2
(-3200 3575);
DISPLAY 1.595745 (-3200 3575);
PAINT GREEN (-3200 3575);
DISPLAY INVISIBLE (-3200 3575);
FORCEPROP 1 LAST PATH I138
J 2
(-2873 3700);
DISPLAY 0.872340 (-2873 3700);
PAINT GREEN (-2873 3700);
DISPLAY INVISIBLE (-2873 3700);
FORCEADD TAP..6
R 2
(-2875 3750);
FORCEPROP 3 LASTPIN (-2925 3750) SIG_NAME M_A_DQS_DN<17>
J 0
(-2915 3760);
DISPLAY 0.659574 (-2915 3760);
PAINT MONO (-2915 3760);
DISPLAY INVISIBLE (-2915 3760);
FORCEPROP 1 LASTPIN (-2925 3750) BN 17
J 2
(-2873 3758);
DISPLAY 0.617021 (-2873 3758);
PAINT PINK (-2873 3758);
FORCEPROP 2 LAST CDS_LIB mstr_standard
J 0
(-2875 3750);
PAINT MONO (-2875 3750);
DISPLAY INVISIBLE (-2875 3750);
FORCEPROP 1 LAST BODY_TYPE PLUMBING
J 2
(-2875 3700);
DISPLAY 1.595745 (-2875 3700);
PAINT GREEN (-2875 3700);
DISPLAY INVISIBLE (-2875 3700);
FORCEPROP 1 LAST HDL_TAP TRUE
J 2
(-3200 3625);
DISPLAY 1.595745 (-3200 3625);
PAINT GREEN (-3200 3625);
DISPLAY INVISIBLE (-3200 3625);
FORCEPROP 1 LAST PATH I139
J 2
(-2873 3750);
DISPLAY 0.872340 (-2873 3750);
PAINT GREEN (-2873 3750);
DISPLAY INVISIBLE (-2873 3750);
FORCEADD TAP..6
(-5600 1150);
FORCEPROP 3 LASTPIN (-5550 1150) SIG_NAME M_A_ECC<1>
J 0
(-5540 1160);
DISPLAY 0.659574 (-5540 1160);
PAINT MONO (-5540 1160);
DISPLAY INVISIBLE (-5540 1160);
FORCEPROP 1 LASTPIN (-5550 1150) BN 1
J 0
(-5602 1158);
DISPLAY 0.617021 (-5602 1158);
PAINT PINK (-5602 1158);
FORCEPROP 2 LAST CDS_LIB mstr_standard
J 0
(-5600 1150);
PAINT MONO (-5600 1150);
DISPLAY INVISIBLE (-5600 1150);
FORCEPROP 1 LAST BODY_TYPE PLUMBING
J 0
(-5600 1100);
DISPLAY 1.595745 (-5600 1100);
PAINT GREEN (-5600 1100);
DISPLAY INVISIBLE (-5600 1100);
FORCEPROP 1 LAST HDL_TAP TRUE
J 0
(-5275 1025);
DISPLAY 1.595745 (-5275 1025);
PAINT GREEN (-5275 1025);
DISPLAY INVISIBLE (-5275 1025);
FORCEPROP 1 LAST PATH I14
J 0
(-5602 1150);
DISPLAY 0.872340 (-5602 1150);
PAINT GREEN (-5602 1150);
DISPLAY INVISIBLE (-5602 1150);
FORCEADD TAP..6
R 2
(-2875 3650);
FORCEPROP 3 LASTPIN (-2925 3650) SIG_NAME M_A_DQS_DN<15>
J 0
(-2915 3660);
DISPLAY 0.659574 (-2915 3660);
PAINT MONO (-2915 3660);
DISPLAY INVISIBLE (-2915 3660);
FORCEPROP 1 LASTPIN (-2925 3650) BN 15
J 2
(-2873 3658);
DISPLAY 0.617021 (-2873 3658);
PAINT PINK (-2873 3658);
FORCEPROP 2 LAST CDS_LIB mstr_standard
J 0
(-2875 3650);
PAINT MONO (-2875 3650);
DISPLAY INVISIBLE (-2875 3650);
FORCEPROP 1 LAST BODY_TYPE PLUMBING
J 2
(-2875 3600);
DISPLAY 1.595745 (-2875 3600);
PAINT GREEN (-2875 3600);
DISPLAY INVISIBLE (-2875 3600);
FORCEPROP 1 LAST HDL_TAP TRUE
J 2
(-3200 3525);
DISPLAY 1.595745 (-3200 3525);
PAINT GREEN (-3200 3525);
DISPLAY INVISIBLE (-3200 3525);
FORCEPROP 1 LAST PATH I140
J 2
(-2873 3650);
DISPLAY 0.872340 (-2873 3650);
PAINT GREEN (-2873 3650);
DISPLAY INVISIBLE (-2873 3650);
FORCEADD TAP..6
R 2
(-2875 3600);
FORCEPROP 3 LASTPIN (-2925 3600) SIG_NAME M_A_DQS_DN<14>
J 0
(-2915 3610);
DISPLAY 0.659574 (-2915 3610);
PAINT MONO (-2915 3610);
DISPLAY INVISIBLE (-2915 3610);
FORCEPROP 1 LASTPIN (-2925 3600) BN 14
J 2
(-2873 3608);
DISPLAY 0.617021 (-2873 3608);
PAINT PINK (-2873 3608);
FORCEPROP 2 LAST CDS_LIB mstr_standard
J 0
(-2875 3600);
PAINT MONO (-2875 3600);
DISPLAY INVISIBLE (-2875 3600);
FORCEPROP 1 LAST BODY_TYPE PLUMBING
J 2
(-2875 3550);
DISPLAY 1.595745 (-2875 3550);
PAINT GREEN (-2875 3550);
DISPLAY INVISIBLE (-2875 3550);
FORCEPROP 1 LAST HDL_TAP TRUE
J 2
(-3200 3475);
DISPLAY 1.595745 (-3200 3475);
PAINT GREEN (-3200 3475);
DISPLAY INVISIBLE (-3200 3475);
FORCEPROP 1 LAST PATH I141
J 2
(-2873 3600);
DISPLAY 0.872340 (-2873 3600);
PAINT GREEN (-2873 3600);
DISPLAY INVISIBLE (-2873 3600);
FORCEADD TAP..6
R 2
(-2875 3550);
FORCEPROP 3 LASTPIN (-2925 3550) SIG_NAME M_A_DQS_DN<13>
J 0
(-2915 3560);
DISPLAY 0.659574 (-2915 3560);
PAINT MONO (-2915 3560);
DISPLAY INVISIBLE (-2915 3560);
FORCEPROP 1 LASTPIN (-2925 3550) BN 13
J 2
(-2873 3558);
DISPLAY 0.617021 (-2873 3558);
PAINT PINK (-2873 3558);
FORCEPROP 2 LAST CDS_LIB mstr_standard
J 0
(-2875 3550);
PAINT MONO (-2875 3550);
DISPLAY INVISIBLE (-2875 3550);
FORCEPROP 1 LAST BODY_TYPE PLUMBING
J 2
(-2875 3500);
DISPLAY 1.595745 (-2875 3500);
PAINT GREEN (-2875 3500);
DISPLAY INVISIBLE (-2875 3500);
FORCEPROP 1 LAST HDL_TAP TRUE
J 2
(-3200 3425);
DISPLAY 1.595745 (-3200 3425);
PAINT GREEN (-3200 3425);
DISPLAY INVISIBLE (-3200 3425);
FORCEPROP 1 LAST PATH I142
J 2
(-2873 3550);
DISPLAY 0.872340 (-2873 3550);
PAINT GREEN (-2873 3550);
DISPLAY INVISIBLE (-2873 3550);
FORCEADD TAP..6
R 2
(-2875 3950);
FORCEPROP 3 LASTPIN (-2925 3950) SIG_NAME M_A_DQS_DP<2>
J 0
(-2915 3960);
DISPLAY 0.659574 (-2915 3960);
PAINT MONO (-2915 3960);
DISPLAY INVISIBLE (-2915 3960);
FORCEPROP 1 LASTPIN (-2925 3950) BN 2
J 2
(-2873 3958);
DISPLAY 0.617021 (-2873 3958);
PAINT PINK (-2873 3958);
FORCEPROP 2 LAST CDS_LIB mstr_standard
J 0
(-2875 3950);
PAINT MONO (-2875 3950);
DISPLAY INVISIBLE (-2875 3950);
FORCEPROP 1 LAST BODY_TYPE PLUMBING
J 2
(-2875 3900);
DISPLAY 1.595745 (-2875 3900);
PAINT GREEN (-2875 3900);
DISPLAY INVISIBLE (-2875 3900);
FORCEPROP 1 LAST HDL_TAP TRUE
J 2
(-3200 3825);
DISPLAY 1.595745 (-3200 3825);
PAINT GREEN (-3200 3825);
DISPLAY INVISIBLE (-3200 3825);
FORCEPROP 1 LAST PATH I143
J 2
(-2873 3950);
DISPLAY 0.872340 (-2873 3950);
PAINT GREEN (-2873 3950);
DISPLAY INVISIBLE (-2873 3950);
FORCEADD TAP..6
R 2
(-2875 4000);
FORCEPROP 3 LASTPIN (-2925 4000) SIG_NAME M_A_DQS_DP<3>
J 0
(-2915 4010);
DISPLAY 0.659574 (-2915 4010);
PAINT MONO (-2915 4010);
DISPLAY INVISIBLE (-2915 4010);
FORCEPROP 1 LASTPIN (-2925 4000) BN 3
J 2
(-2873 4008);
DISPLAY 0.617021 (-2873 4008);
PAINT PINK (-2873 4008);
FORCEPROP 2 LAST CDS_LIB mstr_standard
J 0
(-2875 4000);
PAINT MONO (-2875 4000);
DISPLAY INVISIBLE (-2875 4000);
FORCEPROP 1 LAST BODY_TYPE PLUMBING
J 2
(-2875 3950);
DISPLAY 1.595745 (-2875 3950);
PAINT GREEN (-2875 3950);
DISPLAY INVISIBLE (-2875 3950);
FORCEPROP 1 LAST HDL_TAP TRUE
J 2
(-3200 3875);
DISPLAY 1.595745 (-3200 3875);
PAINT GREEN (-3200 3875);
DISPLAY INVISIBLE (-3200 3875);
FORCEPROP 1 LAST PATH I144
J 2
(-2873 4000);
DISPLAY 0.872340 (-2873 4000);
PAINT GREEN (-2873 4000);
DISPLAY INVISIBLE (-2873 4000);
FORCEADD TAP..6
R 2
(-2875 3900);
FORCEPROP 3 LASTPIN (-2925 3900) SIG_NAME M_A_DQS_DP<1>
J 0
(-2915 3910);
DISPLAY 0.659574 (-2915 3910);
PAINT MONO (-2915 3910);
DISPLAY INVISIBLE (-2915 3910);
FORCEPROP 1 LASTPIN (-2925 3900) BN 1
J 2
(-2873 3908);
DISPLAY 0.617021 (-2873 3908);
PAINT PINK (-2873 3908);
FORCEPROP 2 LAST CDS_LIB mstr_standard
J 0
(-2875 3900);
PAINT MONO (-2875 3900);
DISPLAY INVISIBLE (-2875 3900);
FORCEPROP 1 LAST BODY_TYPE PLUMBING
J 2
(-2875 3850);
DISPLAY 1.595745 (-2875 3850);
PAINT GREEN (-2875 3850);
DISPLAY INVISIBLE (-2875 3850);
FORCEPROP 1 LAST HDL_TAP TRUE
J 2
(-3200 3775);
DISPLAY 1.595745 (-3200 3775);
PAINT GREEN (-3200 3775);
DISPLAY INVISIBLE (-3200 3775);
FORCEPROP 1 LAST PATH I145
J 2
(-2873 3900);
DISPLAY 0.872340 (-2873 3900);
PAINT GREEN (-2873 3900);
DISPLAY INVISIBLE (-2873 3900);
FORCEADD TAP..6
R 2
(-2875 3850);
FORCEPROP 3 LASTPIN (-2925 3850) SIG_NAME M_A_DQS_DP<0>
J 0
(-2915 3860);
DISPLAY 0.659574 (-2915 3860);
PAINT MONO (-2915 3860);
DISPLAY INVISIBLE (-2915 3860);
FORCEPROP 1 LASTPIN (-2925 3850) BN 0
J 2
(-2873 3858);
DISPLAY 0.617021 (-2873 3858);
PAINT PINK (-2873 3858);
FORCEPROP 2 LAST CDS_LIB mstr_standard
J 0
(-2875 3850);
PAINT MONO (-2875 3850);
DISPLAY INVISIBLE (-2875 3850);
FORCEPROP 1 LAST BODY_TYPE PLUMBING
J 2
(-2875 3800);
DISPLAY 1.595745 (-2875 3800);
PAINT GREEN (-2875 3800);
DISPLAY INVISIBLE (-2875 3800);
FORCEPROP 1 LAST HDL_TAP TRUE
J 2
(-3200 3725);
DISPLAY 1.595745 (-3200 3725);
PAINT GREEN (-3200 3725);
DISPLAY INVISIBLE (-3200 3725);
FORCEPROP 1 LAST PATH I146
J 2
(-2873 3850);
DISPLAY 0.872340 (-2873 3850);
PAINT GREEN (-2873 3850);
DISPLAY INVISIBLE (-2873 3850);
FORCEADD OFFPAGE..2
(-2025 550);
FORCEPROP 2 LAST $XR0 43 
J 0
(-1836 550);
DISPLAY 0.638298 (-1836 550);
PAINT MONO (-1836 550);
FORCEPROP 2 LAST $XR1 44 
J 0
(-1746 550);
DISPLAY 0.638298 (-1746 550);
PAINT MONO (-1746 550);
FORCEPROP 2 LAST CDS_LIB mstr_standard
J 0
(-2025 550);
PAINT MONO (-2025 550);
DISPLAY INVISIBLE (-2025 550);
FORCEPROP 1 LAST OFFPAGE TRUE
J 0
(-1700 425);
DISPLAY 1.170213 (-1700 425);
PAINT GREEN (-1700 425);
DISPLAY INVISIBLE (-1700 425);
FORCEPROP 1 LAST COMMENT_BODY TRUE
J 0
(-2070 455);
DISPLAY 1.170213 (-2070 455);
PAINT GREEN (-2070 455);
DISPLAY INVISIBLE (-2070 455);
FORCEPROP 2 LAST PATH I147
J 0
(-1850 625);
DISPLAY 1.021277 (-1850 625);
PAINT ORANGE (-1850 625);
DISPLAY INVISIBLE (-1850 625);
FORCEADD OFFPAGE..4
(-2025 600);
FORCEPROP 2 LAST $XR0 43 
J 0
(-1839 600);
DISPLAY 0.638298 (-1839 600);
PAINT MONO (-1839 600);
FORCEPROP 2 LAST $XR1 44 
J 0
(-1749 600);
DISPLAY 0.638298 (-1749 600);
PAINT MONO (-1749 600);
FORCEPROP 2 LAST CDS_LIB mstr_standard
J 0
(-2025 600);
PAINT MONO (-2025 600);
DISPLAY INVISIBLE (-2025 600);
FORCEPROP 1 LAST OFFPAGE TRUE
J 0
(-1700 475);
DISPLAY 1.170213 (-1700 475);
PAINT GREEN (-1700 475);
DISPLAY INVISIBLE (-1700 475);
FORCEPROP 1 LAST COMMENT_BODY TRUE
J 0
(-2050 500);
DISPLAY 1.170213 (-2050 500);
PAINT GREEN (-2050 500);
DISPLAY INVISIBLE (-2050 500);
FORCEPROP 2 LAST PATH I148
J 0
(-1850 675);
DISPLAY 1.021277 (-1850 675);
PAINT ORANGE (-1850 675);
DISPLAY INVISIBLE (-1850 675);
FORCEADD OFFPAGE..2
(-2025 650);
FORCEPROP 2 LAST $XR0 43 
J 0
(-1836 650);
DISPLAY 0.638298 (-1836 650);
PAINT MONO (-1836 650);
FORCEPROP 2 LAST $XR1 44 
J 0
(-1746 650);
DISPLAY 0.638298 (-1746 650);
PAINT MONO (-1746 650);
FORCEPROP 2 LAST CDS_LIB mstr_standard
J 0
(-2025 650);
PAINT MONO (-2025 650);
DISPLAY INVISIBLE (-2025 650);
FORCEPROP 1 LAST OFFPAGE TRUE
J 0
(-1700 525);
DISPLAY 1.170213 (-1700 525);
PAINT GREEN (-1700 525);
DISPLAY INVISIBLE (-1700 525);
FORCEPROP 1 LAST COMMENT_BODY TRUE
J 0
(-2070 555);
DISPLAY 1.170213 (-2070 555);
PAINT GREEN (-2070 555);
DISPLAY INVISIBLE (-2070 555);
FORCEPROP 2 LAST PATH I149
J 0
(-1850 725);
DISPLAY 1.021277 (-1850 725);
PAINT ORANGE (-1850 725);
DISPLAY INVISIBLE (-1850 725);
FORCEADD TAP..6
(-5600 1200);
FORCEPROP 3 LASTPIN (-5550 1200) SIG_NAME M_A_ECC<2>
J 0
(-5540 1210);
DISPLAY 0.659574 (-5540 1210);
PAINT MONO (-5540 1210);
DISPLAY INVISIBLE (-5540 1210);
FORCEPROP 1 LASTPIN (-5550 1200) BN 2
J 0
(-5602 1208);
DISPLAY 0.617021 (-5602 1208);
PAINT PINK (-5602 1208);
FORCEPROP 2 LAST CDS_LIB mstr_standard
J 0
(-5600 1200);
PAINT MONO (-5600 1200);
DISPLAY INVISIBLE (-5600 1200);
FORCEPROP 1 LAST BODY_TYPE PLUMBING
J 0
(-5600 1150);
DISPLAY 1.595745 (-5600 1150);
PAINT GREEN (-5600 1150);
DISPLAY INVISIBLE (-5600 1150);
FORCEPROP 1 LAST HDL_TAP TRUE
J 0
(-5275 1075);
DISPLAY 1.595745 (-5275 1075);
PAINT GREEN (-5275 1075);
DISPLAY INVISIBLE (-5275 1075);
FORCEPROP 1 LAST PATH I15
J 0
(-5602 1200);
DISPLAY 0.872340 (-5602 1200);
PAINT GREEN (-5602 1200);
DISPLAY INVISIBLE (-5602 1200);
FORCEADD OFFPAGE..2
(-2025 950);
FORCEPROP 2 LAST $XR0 43 
J 0
(-1836 950);
DISPLAY 0.638298 (-1836 950);
PAINT MONO (-1836 950);
FORCEPROP 2 LAST $XR1 44 
J 0
(-1746 950);
DISPLAY 0.638298 (-1746 950);
PAINT MONO (-1746 950);
FORCEPROP 2 LAST CDS_LIB mstr_standard
J 0
(-2025 950);
PAINT MONO (-2025 950);
DISPLAY INVISIBLE (-2025 950);
FORCEPROP 1 LAST OFFPAGE TRUE
J 0
(-1700 825);
DISPLAY 1.170213 (-1700 825);
PAINT GREEN (-1700 825);
DISPLAY INVISIBLE (-1700 825);
FORCEPROP 1 LAST COMMENT_BODY TRUE
J 0
(-2070 855);
DISPLAY 1.170213 (-2070 855);
PAINT GREEN (-2070 855);
DISPLAY INVISIBLE (-2070 855);
FORCEPROP 2 LAST PATH I150
J 0
(-1850 1025);
DISPLAY 1.021277 (-1850 1025);
PAINT ORANGE (-1850 1025);
DISPLAY INVISIBLE (-1850 1025);
FORCEADD OFFPAGE..2
(-2025 850);
FORCEPROP 2 LAST $XR0 43 
J 0
(-1836 850);
DISPLAY 0.638298 (-1836 850);
PAINT MONO (-1836 850);
FORCEPROP 2 LAST $XR1 44 
J 0
(-1746 850);
DISPLAY 0.638298 (-1746 850);
PAINT MONO (-1746 850);
FORCEPROP 2 LAST CDS_LIB mstr_standard
J 0
(-2025 850);
PAINT MONO (-2025 850);
DISPLAY INVISIBLE (-2025 850);
FORCEPROP 1 LAST OFFPAGE TRUE
J 0
(-1700 725);
DISPLAY 1.170213 (-1700 725);
PAINT GREEN (-1700 725);
DISPLAY INVISIBLE (-1700 725);
FORCEPROP 1 LAST COMMENT_BODY TRUE
J 0
(-2070 755);
DISPLAY 1.170213 (-2070 755);
PAINT GREEN (-2070 755);
DISPLAY INVISIBLE (-2070 755);
FORCEPROP 2 LAST PATH I151
J 0
(-1850 925);
DISPLAY 1.021277 (-1850 925);
PAINT ORANGE (-1850 925);
DISPLAY INVISIBLE (-1850 925);
FORCEADD OFFPAGE..2
(-2025 1400);
FORCEPROP 2 LAST $XR0 43 
J 0
(-1836 1400);
DISPLAY 0.638298 (-1836 1400);
PAINT MONO (-1836 1400);
FORCEPROP 2 LAST $XR1 44 
J 0
(-1746 1400);
DISPLAY 0.638298 (-1746 1400);
PAINT MONO (-1746 1400);
FORCEPROP 2 LAST CDS_LIB mstr_standard
J 0
(-2025 1400);
PAINT MONO (-2025 1400);
DISPLAY INVISIBLE (-2025 1400);
FORCEPROP 1 LAST OFFPAGE TRUE
J 0
(-1700 1275);
DISPLAY 1.170213 (-1700 1275);
PAINT GREEN (-1700 1275);
DISPLAY INVISIBLE (-1700 1275);
FORCEPROP 1 LAST COMMENT_BODY TRUE
J 0
(-2070 1305);
DISPLAY 1.170213 (-2070 1305);
PAINT GREEN (-2070 1305);
DISPLAY INVISIBLE (-2070 1305);
FORCEPROP 2 LAST PATH I152
J 0
(-1850 1475);
DISPLAY 1.021277 (-1850 1475);
PAINT ORANGE (-1850 1475);
DISPLAY INVISIBLE (-1850 1475);
FORCEADD OFFPAGE..2
(-2025 1650);
FORCEPROP 2 LAST $XR0 43 
J 0
(-1836 1650);
DISPLAY 0.638298 (-1836 1650);
PAINT MONO (-1836 1650);
FORCEPROP 2 LAST $XR1 44 
J 0
(-1746 1650);
DISPLAY 0.638298 (-1746 1650);
PAINT MONO (-1746 1650);
FORCEPROP 2 LAST CDS_LIB mstr_standard
J 0
(-2025 1650);
PAINT MONO (-2025 1650);
DISPLAY INVISIBLE (-2025 1650);
FORCEPROP 1 LAST OFFPAGE TRUE
J 0
(-1700 1525);
DISPLAY 1.170213 (-1700 1525);
PAINT GREEN (-1700 1525);
DISPLAY INVISIBLE (-1700 1525);
FORCEPROP 1 LAST COMMENT_BODY TRUE
J 0
(-2070 1555);
DISPLAY 1.170213 (-2070 1555);
PAINT GREEN (-2070 1555);
DISPLAY INVISIBLE (-2070 1555);
FORCEPROP 2 LAST PATH I153
J 0
(-1850 1725);
DISPLAY 1.021277 (-1850 1725);
PAINT ORANGE (-1850 1725);
DISPLAY INVISIBLE (-1850 1725);
FORCEADD OFFPAGE..2
(-2025 1900);
FORCEPROP 2 LAST $XR0 43 
J 0
(-1836 1900);
DISPLAY 0.638298 (-1836 1900);
PAINT MONO (-1836 1900);
FORCEPROP 2 LAST $XR1 44 
J 0
(-1746 1900);
DISPLAY 0.638298 (-1746 1900);
PAINT MONO (-1746 1900);
FORCEPROP 2 LAST CDS_LIB mstr_standard
J 0
(-2025 1900);
PAINT MONO (-2025 1900);
DISPLAY INVISIBLE (-2025 1900);
FORCEPROP 1 LAST OFFPAGE TRUE
J 0
(-1700 1775);
DISPLAY 1.170213 (-1700 1775);
PAINT GREEN (-1700 1775);
DISPLAY INVISIBLE (-1700 1775);
FORCEPROP 1 LAST COMMENT_BODY TRUE
J 0
(-2070 1805);
DISPLAY 1.170213 (-2070 1805);
PAINT GREEN (-2070 1805);
DISPLAY INVISIBLE (-2070 1805);
FORCEPROP 2 LAST PATH I154
J 0
(-1850 1975);
DISPLAY 1.021277 (-1850 1975);
PAINT ORANGE (-1850 1975);
DISPLAY INVISIBLE (-1850 1975);
FORCEADD OFFPAGE..2
(-2025 2850);
FORCEPROP 2 LAST $XR0 43 
J 0
(-1836 2850);
DISPLAY 0.638298 (-1836 2850);
PAINT MONO (-1836 2850);
FORCEPROP 2 LAST $XR1 44 
J 0
(-1746 2850);
DISPLAY 0.638298 (-1746 2850);
PAINT MONO (-1746 2850);
FORCEPROP 2 LAST CDS_LIB mstr_standard
J 0
(-2025 2850);
PAINT MONO (-2025 2850);
DISPLAY INVISIBLE (-2025 2850);
FORCEPROP 1 LAST OFFPAGE TRUE
J 0
(-1700 2725);
DISPLAY 1.170213 (-1700 2725);
PAINT GREEN (-1700 2725);
DISPLAY INVISIBLE (-1700 2725);
FORCEPROP 1 LAST COMMENT_BODY TRUE
J 0
(-2070 2755);
DISPLAY 1.170213 (-2070 2755);
PAINT GREEN (-2070 2755);
DISPLAY INVISIBLE (-2070 2755);
FORCEPROP 2 LAST PATH I155
J 0
(-1850 2925);
DISPLAY 1.021277 (-1850 2925);
PAINT ORANGE (-1850 2925);
DISPLAY INVISIBLE (-1850 2925);
FORCEADD OFFPAGE..3
(-2025 3800);
FORCEPROP 2 LAST $XR0 43 
J 0
(-1811 3800);
DISPLAY 0.638298 (-1811 3800);
PAINT MONO (-1811 3800);
FORCEPROP 2 LAST $XR1 44 
J 0
(-1721 3800);
DISPLAY 0.638298 (-1721 3800);
PAINT MONO (-1721 3800);
FORCEPROP 2 LAST CDS_LIB mstr_standard
J 0
(-2025 3800);
PAINT MONO (-2025 3800);
DISPLAY INVISIBLE (-2025 3800);
FORCEPROP 1 LAST OFFPAGE TRUE
J 0
(-1700 3675);
DISPLAY 1.170213 (-1700 3675);
PAINT GREEN (-1700 3675);
DISPLAY INVISIBLE (-1700 3675);
FORCEPROP 1 LAST COMMENT_BODY TRUE
J 0
(-2075 3700);
DISPLAY 1.170213 (-2075 3700);
PAINT GREEN (-2075 3700);
DISPLAY INVISIBLE (-2075 3700);
FORCEPROP 2 LAST PATH I156
J 0
(-1825 3875);
DISPLAY 1.021277 (-1825 3875);
PAINT ORANGE (-1825 3875);
DISPLAY INVISIBLE (-1825 3875);
FORCEADD TAP..6
R 2
(-2875 4050);
FORCEPROP 3 LASTPIN (-2925 4050) SIG_NAME M_A_DQS_DP<4>
J 0
(-2915 4060);
DISPLAY 0.659574 (-2915 4060);
PAINT MONO (-2915 4060);
DISPLAY INVISIBLE (-2915 4060);
FORCEPROP 1 LASTPIN (-2925 4050) BN 4
J 2
(-2873 4058);
DISPLAY 0.617021 (-2873 4058);
PAINT PINK (-2873 4058);
FORCEPROP 2 LAST CDS_LIB mstr_standard
J 0
(-2875 4050);
PAINT MONO (-2875 4050);
DISPLAY INVISIBLE (-2875 4050);
FORCEPROP 1 LAST BODY_TYPE PLUMBING
J 2
(-2875 4000);
DISPLAY 1.595745 (-2875 4000);
PAINT GREEN (-2875 4000);
DISPLAY INVISIBLE (-2875 4000);
FORCEPROP 1 LAST HDL_TAP TRUE
J 2
(-3200 3925);
DISPLAY 1.595745 (-3200 3925);
PAINT GREEN (-3200 3925);
DISPLAY INVISIBLE (-3200 3925);
FORCEPROP 1 LAST PATH I157
J 2
(-2873 4050);
DISPLAY 0.872340 (-2873 4050);
PAINT GREEN (-2873 4050);
DISPLAY INVISIBLE (-2873 4050);
FORCEADD TAP..6
R 2
(-2875 4100);
FORCEPROP 3 LASTPIN (-2925 4100) SIG_NAME M_A_DQS_DP<5>
J 0
(-2915 4110);
DISPLAY 0.659574 (-2915 4110);
PAINT MONO (-2915 4110);
DISPLAY INVISIBLE (-2915 4110);
FORCEPROP 1 LASTPIN (-2925 4100) BN 5
J 2
(-2873 4108);
DISPLAY 0.617021 (-2873 4108);
PAINT PINK (-2873 4108);
FORCEPROP 2 LAST CDS_LIB mstr_standard
J 0
(-2875 4100);
PAINT MONO (-2875 4100);
DISPLAY INVISIBLE (-2875 4100);
FORCEPROP 1 LAST BODY_TYPE PLUMBING
J 2
(-2875 4050);
DISPLAY 1.595745 (-2875 4050);
PAINT GREEN (-2875 4050);
DISPLAY INVISIBLE (-2875 4050);
FORCEPROP 1 LAST HDL_TAP TRUE
J 2
(-3200 3975);
DISPLAY 1.595745 (-3200 3975);
PAINT GREEN (-3200 3975);
DISPLAY INVISIBLE (-3200 3975);
FORCEPROP 1 LAST PATH I158
J 2
(-2873 4100);
DISPLAY 0.872340 (-2873 4100);
PAINT GREEN (-2873 4100);
DISPLAY INVISIBLE (-2873 4100);
FORCEADD TAP..6
R 2
(-2875 4150);
FORCEPROP 3 LASTPIN (-2925 4150) SIG_NAME M_A_DQS_DP<6>
J 0
(-2915 4160);
DISPLAY 0.659574 (-2915 4160);
PAINT MONO (-2915 4160);
DISPLAY INVISIBLE (-2915 4160);
FORCEPROP 1 LASTPIN (-2925 4150) BN 6
J 2
(-2873 4158);
DISPLAY 0.617021 (-2873 4158);
PAINT PINK (-2873 4158);
FORCEPROP 2 LAST CDS_LIB mstr_standard
J 0
(-2875 4150);
PAINT MONO (-2875 4150);
DISPLAY INVISIBLE (-2875 4150);
FORCEPROP 1 LAST BODY_TYPE PLUMBING
J 2
(-2875 4100);
DISPLAY 1.595745 (-2875 4100);
PAINT GREEN (-2875 4100);
DISPLAY INVISIBLE (-2875 4100);
FORCEPROP 1 LAST HDL_TAP TRUE
J 2
(-3200 4025);
DISPLAY 1.595745 (-3200 4025);
PAINT GREEN (-3200 4025);
DISPLAY INVISIBLE (-3200 4025);
FORCEPROP 1 LAST PATH I159
J 2
(-2873 4150);
DISPLAY 0.872340 (-2873 4150);
PAINT GREEN (-2873 4150);
DISPLAY INVISIBLE (-2873 4150);
FORCEADD TAP..6
(-5600 1300);
FORCEPROP 3 LASTPIN (-5550 1300) SIG_NAME M_A_ECC<4>
J 0
(-5540 1310);
DISPLAY 0.659574 (-5540 1310);
PAINT MONO (-5540 1310);
DISPLAY INVISIBLE (-5540 1310);
FORCEPROP 1 LASTPIN (-5550 1300) BN 4
J 0
(-5602 1308);
DISPLAY 0.617021 (-5602 1308);
PAINT PINK (-5602 1308);
FORCEPROP 2 LAST CDS_LIB mstr_standard
J 0
(-5600 1300);
PAINT MONO (-5600 1300);
DISPLAY INVISIBLE (-5600 1300);
FORCEPROP 1 LAST BODY_TYPE PLUMBING
J 0
(-5600 1250);
DISPLAY 1.595745 (-5600 1250);
PAINT GREEN (-5600 1250);
DISPLAY INVISIBLE (-5600 1250);
FORCEPROP 1 LAST HDL_TAP TRUE
J 0
(-5275 1175);
DISPLAY 1.595745 (-5275 1175);
PAINT GREEN (-5275 1175);
DISPLAY INVISIBLE (-5275 1175);
FORCEPROP 1 LAST PATH I16
J 0
(-5602 1300);
DISPLAY 0.872340 (-5602 1300);
PAINT GREEN (-5602 1300);
DISPLAY INVISIBLE (-5602 1300);
FORCEADD TAP..6
R 2
(-2875 4300);
FORCEPROP 3 LASTPIN (-2925 4300) SIG_NAME M_A_DQS_DP<9>
J 0
(-2915 4310);
DISPLAY 0.659574 (-2915 4310);
PAINT MONO (-2915 4310);
DISPLAY INVISIBLE (-2915 4310);
FORCEPROP 1 LASTPIN (-2925 4300) BN 9
J 2
(-2873 4308);
DISPLAY 0.617021 (-2873 4308);
PAINT PINK (-2873 4308);
FORCEPROP 2 LAST CDS_LIB mstr_standard
J 0
(-2875 4300);
PAINT MONO (-2875 4300);
DISPLAY INVISIBLE (-2875 4300);
FORCEPROP 1 LAST BODY_TYPE PLUMBING
J 2
(-2875 4250);
DISPLAY 1.595745 (-2875 4250);
PAINT GREEN (-2875 4250);
DISPLAY INVISIBLE (-2875 4250);
FORCEPROP 1 LAST HDL_TAP TRUE
J 2
(-3200 4175);
DISPLAY 1.595745 (-3200 4175);
PAINT GREEN (-3200 4175);
DISPLAY INVISIBLE (-3200 4175);
FORCEPROP 1 LAST PATH I160
J 2
(-2873 4300);
DISPLAY 0.872340 (-2873 4300);
PAINT GREEN (-2873 4300);
DISPLAY INVISIBLE (-2873 4300);
FORCEADD TAP..6
R 2
(-2875 4250);
FORCEPROP 3 LASTPIN (-2925 4250) SIG_NAME M_A_DQS_DP<8>
J 0
(-2915 4260);
DISPLAY 0.659574 (-2915 4260);
PAINT MONO (-2915 4260);
DISPLAY INVISIBLE (-2915 4260);
FORCEPROP 1 LASTPIN (-2925 4250) BN 8
J 2
(-2873 4258);
DISPLAY 0.617021 (-2873 4258);
PAINT PINK (-2873 4258);
FORCEPROP 2 LAST CDS_LIB mstr_standard
J 0
(-2875 4250);
PAINT MONO (-2875 4250);
DISPLAY INVISIBLE (-2875 4250);
FORCEPROP 1 LAST BODY_TYPE PLUMBING
J 2
(-2875 4200);
DISPLAY 1.595745 (-2875 4200);
PAINT GREEN (-2875 4200);
DISPLAY INVISIBLE (-2875 4200);
FORCEPROP 1 LAST HDL_TAP TRUE
J 2
(-3200 4125);
DISPLAY 1.595745 (-3200 4125);
PAINT GREEN (-3200 4125);
DISPLAY INVISIBLE (-3200 4125);
FORCEPROP 1 LAST PATH I161
J 2
(-2873 4250);
DISPLAY 0.872340 (-2873 4250);
PAINT GREEN (-2873 4250);
DISPLAY INVISIBLE (-2873 4250);
FORCEADD TAP..6
R 2
(-2875 4200);
FORCEPROP 3 LASTPIN (-2925 4200) SIG_NAME M_A_DQS_DP<7>
J 0
(-2915 4210);
DISPLAY 0.659574 (-2915 4210);
PAINT MONO (-2915 4210);
DISPLAY INVISIBLE (-2915 4210);
FORCEPROP 1 LASTPIN (-2925 4200) BN 7
J 2
(-2873 4208);
DISPLAY 0.617021 (-2873 4208);
PAINT PINK (-2873 4208);
FORCEPROP 2 LAST CDS_LIB mstr_standard
J 0
(-2875 4200);
PAINT MONO (-2875 4200);
DISPLAY INVISIBLE (-2875 4200);
FORCEPROP 1 LAST BODY_TYPE PLUMBING
J 2
(-2875 4150);
DISPLAY 1.595745 (-2875 4150);
PAINT GREEN (-2875 4150);
DISPLAY INVISIBLE (-2875 4150);
FORCEPROP 1 LAST HDL_TAP TRUE
J 2
(-3200 4075);
DISPLAY 1.595745 (-3200 4075);
PAINT GREEN (-3200 4075);
DISPLAY INVISIBLE (-3200 4075);
FORCEPROP 1 LAST PATH I162
J 2
(-2873 4200);
DISPLAY 0.872340 (-2873 4200);
PAINT GREEN (-2873 4200);
DISPLAY INVISIBLE (-2873 4200);
FORCEADD TAP..6
R 2
(-2875 4450);
FORCEPROP 3 LASTPIN (-2925 4450) SIG_NAME M_A_DQS_DP<12>
J 0
(-2915 4460);
DISPLAY 0.659574 (-2915 4460);
PAINT MONO (-2915 4460);
DISPLAY INVISIBLE (-2915 4460);
FORCEPROP 1 LASTPIN (-2925 4450) BN 12
J 2
(-2873 4458);
DISPLAY 0.617021 (-2873 4458);
PAINT PINK (-2873 4458);
FORCEPROP 2 LAST CDS_LIB mstr_standard
J 0
(-2875 4450);
PAINT MONO (-2875 4450);
DISPLAY INVISIBLE (-2875 4450);
FORCEPROP 1 LAST BODY_TYPE PLUMBING
J 2
(-2875 4400);
DISPLAY 1.595745 (-2875 4400);
PAINT GREEN (-2875 4400);
DISPLAY INVISIBLE (-2875 4400);
FORCEPROP 1 LAST HDL_TAP TRUE
J 2
(-3200 4325);
DISPLAY 1.595745 (-3200 4325);
PAINT GREEN (-3200 4325);
DISPLAY INVISIBLE (-3200 4325);
FORCEPROP 1 LAST PATH I163
J 2
(-2873 4450);
DISPLAY 0.872340 (-2873 4450);
PAINT GREEN (-2873 4450);
DISPLAY INVISIBLE (-2873 4450);
FORCEADD TAP..6
R 2
(-2875 4500);
FORCEPROP 3 LASTPIN (-2925 4500) SIG_NAME M_A_DQS_DP<13>
J 0
(-2915 4510);
DISPLAY 0.659574 (-2915 4510);
PAINT MONO (-2915 4510);
DISPLAY INVISIBLE (-2915 4510);
FORCEPROP 1 LASTPIN (-2925 4500) BN 13
J 2
(-2873 4508);
DISPLAY 0.617021 (-2873 4508);
PAINT PINK (-2873 4508);
FORCEPROP 2 LAST CDS_LIB mstr_standard
J 0
(-2875 4500);
PAINT MONO (-2875 4500);
DISPLAY INVISIBLE (-2875 4500);
FORCEPROP 1 LAST BODY_TYPE PLUMBING
J 2
(-2875 4450);
DISPLAY 1.595745 (-2875 4450);
PAINT GREEN (-2875 4450);
DISPLAY INVISIBLE (-2875 4450);
FORCEPROP 1 LAST HDL_TAP TRUE
J 2
(-3200 4375);
DISPLAY 1.595745 (-3200 4375);
PAINT GREEN (-3200 4375);
DISPLAY INVISIBLE (-3200 4375);
FORCEPROP 1 LAST PATH I164
J 2
(-2873 4500);
DISPLAY 0.872340 (-2873 4500);
PAINT GREEN (-2873 4500);
DISPLAY INVISIBLE (-2873 4500);
FORCEADD TAP..6
R 2
(-2875 4550);
FORCEPROP 3 LASTPIN (-2925 4550) SIG_NAME M_A_DQS_DP<14>
J 0
(-2915 4560);
DISPLAY 0.659574 (-2915 4560);
PAINT MONO (-2915 4560);
DISPLAY INVISIBLE (-2915 4560);
FORCEPROP 1 LASTPIN (-2925 4550) BN 14
J 2
(-2873 4558);
DISPLAY 0.617021 (-2873 4558);
PAINT PINK (-2873 4558);
FORCEPROP 2 LAST CDS_LIB mstr_standard
J 0
(-2875 4550);
PAINT MONO (-2875 4550);
DISPLAY INVISIBLE (-2875 4550);
FORCEPROP 1 LAST BODY_TYPE PLUMBING
J 2
(-2875 4500);
DISPLAY 1.595745 (-2875 4500);
PAINT GREEN (-2875 4500);
DISPLAY INVISIBLE (-2875 4500);
FORCEPROP 1 LAST HDL_TAP TRUE
J 2
(-3200 4425);
DISPLAY 1.595745 (-3200 4425);
PAINT GREEN (-3200 4425);
DISPLAY INVISIBLE (-3200 4425);
FORCEPROP 1 LAST PATH I165
J 2
(-2873 4550);
DISPLAY 0.872340 (-2873 4550);
PAINT GREEN (-2873 4550);
DISPLAY INVISIBLE (-2873 4550);
FORCEADD TAP..6
R 2
(-2875 4400);
FORCEPROP 3 LASTPIN (-2925 4400) SIG_NAME M_A_DQS_DP<11>
J 0
(-2915 4410);
DISPLAY 0.659574 (-2915 4410);
PAINT MONO (-2915 4410);
DISPLAY INVISIBLE (-2915 4410);
FORCEPROP 1 LASTPIN (-2925 4400) BN 11
J 2
(-2873 4408);
DISPLAY 0.617021 (-2873 4408);
PAINT PINK (-2873 4408);
FORCEPROP 2 LAST CDS_LIB mstr_standard
J 0
(-2875 4400);
PAINT MONO (-2875 4400);
DISPLAY INVISIBLE (-2875 4400);
FORCEPROP 1 LAST BODY_TYPE PLUMBING
J 2
(-2875 4350);
DISPLAY 1.595745 (-2875 4350);
PAINT GREEN (-2875 4350);
DISPLAY INVISIBLE (-2875 4350);
FORCEPROP 1 LAST HDL_TAP TRUE
J 2
(-3200 4275);
DISPLAY 1.595745 (-3200 4275);
PAINT GREEN (-3200 4275);
DISPLAY INVISIBLE (-3200 4275);
FORCEPROP 1 LAST PATH I166
J 2
(-2873 4400);
DISPLAY 0.872340 (-2873 4400);
PAINT GREEN (-2873 4400);
DISPLAY INVISIBLE (-2873 4400);
FORCEADD TAP..6
R 2
(-2875 4350);
FORCEPROP 3 LASTPIN (-2925 4350) SIG_NAME M_A_DQS_DP<10>
J 0
(-2915 4360);
DISPLAY 0.659574 (-2915 4360);
PAINT MONO (-2915 4360);
DISPLAY INVISIBLE (-2915 4360);
FORCEPROP 1 LASTPIN (-2925 4350) BN 10
J 2
(-2873 4358);
DISPLAY 0.617021 (-2873 4358);
PAINT PINK (-2873 4358);
FORCEPROP 2 LAST CDS_LIB mstr_standard
J 0
(-2875 4350);
PAINT MONO (-2875 4350);
DISPLAY INVISIBLE (-2875 4350);
FORCEPROP 1 LAST BODY_TYPE PLUMBING
J 2
(-2875 4300);
DISPLAY 1.595745 (-2875 4300);
PAINT GREEN (-2875 4300);
DISPLAY INVISIBLE (-2875 4300);
FORCEPROP 1 LAST HDL_TAP TRUE
J 2
(-3200 4225);
DISPLAY 1.595745 (-3200 4225);
PAINT GREEN (-3200 4225);
DISPLAY INVISIBLE (-3200 4225);
FORCEPROP 1 LAST PATH I167
J 2
(-2873 4350);
DISPLAY 0.872340 (-2873 4350);
PAINT GREEN (-2873 4350);
DISPLAY INVISIBLE (-2873 4350);
FORCEADD TAP..6
R 2
(-2875 4700);
FORCEPROP 3 LASTPIN (-2925 4700) SIG_NAME M_A_DQS_DP<17>
J 0
(-2915 4710);
DISPLAY 0.659574 (-2915 4710);
PAINT MONO (-2915 4710);
DISPLAY INVISIBLE (-2915 4710);
FORCEPROP 1 LASTPIN (-2925 4700) BN 17
J 2
(-2873 4708);
DISPLAY 0.617021 (-2873 4708);
PAINT PINK (-2873 4708);
FORCEPROP 2 LAST CDS_LIB mstr_standard
J 2
(-2875 4700);
PAINT MONO (-2875 4700);
DISPLAY INVISIBLE (-2875 4700);
FORCEPROP 1 LAST BODY_TYPE PLUMBING
J 2
(-2875 4650);
DISPLAY 1.595745 (-2875 4650);
PAINT GREEN (-2875 4650);
DISPLAY INVISIBLE (-2875 4650);
FORCEPROP 1 LAST HDL_TAP TRUE
J 2
(-3200 4575);
DISPLAY 1.595745 (-3200 4575);
PAINT GREEN (-3200 4575);
DISPLAY INVISIBLE (-3200 4575);
FORCEPROP 1 LAST PATH I168
J 2
(-2873 4700);
DISPLAY 0.872340 (-2873 4700);
PAINT GREEN (-2873 4700);
DISPLAY INVISIBLE (-2873 4700);
FORCEADD TAP..6
R 2
(-2875 4600);
FORCEPROP 3 LASTPIN (-2925 4600) SIG_NAME M_A_DQS_DP<15>
J 0
(-2915 4610);
DISPLAY 0.659574 (-2915 4610);
PAINT MONO (-2915 4610);
DISPLAY INVISIBLE (-2915 4610);
FORCEPROP 1 LASTPIN (-2925 4600) BN 15
J 2
(-2873 4608);
DISPLAY 0.617021 (-2873 4608);
PAINT PINK (-2873 4608);
FORCEPROP 2 LAST CDS_LIB mstr_standard
J 0
(-2875 4600);
PAINT MONO (-2875 4600);
DISPLAY INVISIBLE (-2875 4600);
FORCEPROP 1 LAST BODY_TYPE PLUMBING
J 2
(-2875 4550);
DISPLAY 1.595745 (-2875 4550);
PAINT GREEN (-2875 4550);
DISPLAY INVISIBLE (-2875 4550);
FORCEPROP 1 LAST HDL_TAP TRUE
J 2
(-3200 4475);
DISPLAY 1.595745 (-3200 4475);
PAINT GREEN (-3200 4475);
DISPLAY INVISIBLE (-3200 4475);
FORCEPROP 1 LAST PATH I169
J 2
(-2873 4600);
DISPLAY 0.872340 (-2873 4600);
PAINT GREEN (-2873 4600);
DISPLAY INVISIBLE (-2873 4600);
FORCEADD TAP..6
(-5600 1250);
FORCEPROP 3 LASTPIN (-5550 1250) SIG_NAME M_A_ECC<3>
J 0
(-5540 1260);
DISPLAY 0.659574 (-5540 1260);
PAINT MONO (-5540 1260);
DISPLAY INVISIBLE (-5540 1260);
FORCEPROP 1 LASTPIN (-5550 1250) BN 3
J 0
(-5602 1258);
DISPLAY 0.617021 (-5602 1258);
PAINT PINK (-5602 1258);
FORCEPROP 2 LAST CDS_LIB mstr_standard
J 0
(-5600 1250);
PAINT MONO (-5600 1250);
DISPLAY INVISIBLE (-5600 1250);
FORCEPROP 1 LAST BODY_TYPE PLUMBING
J 0
(-5600 1200);
DISPLAY 1.595745 (-5600 1200);
PAINT GREEN (-5600 1200);
DISPLAY INVISIBLE (-5600 1200);
FORCEPROP 1 LAST HDL_TAP TRUE
J 0
(-5275 1125);
DISPLAY 1.595745 (-5275 1125);
PAINT GREEN (-5275 1125);
DISPLAY INVISIBLE (-5275 1125);
FORCEPROP 1 LAST PATH I17
J 0
(-5602 1250);
DISPLAY 0.872340 (-5602 1250);
PAINT GREEN (-5602 1250);
DISPLAY INVISIBLE (-5602 1250);
FORCEADD TAP..6
R 2
(-2875 4650);
FORCEPROP 3 LASTPIN (-2925 4650) SIG_NAME M_A_DQS_DP<16>
J 0
(-2915 4660);
DISPLAY 0.659574 (-2915 4660);
PAINT MONO (-2915 4660);
DISPLAY INVISIBLE (-2915 4660);
FORCEPROP 1 LASTPIN (-2925 4650) BN 16
J 2
(-2873 4658);
DISPLAY 0.617021 (-2873 4658);
PAINT PINK (-2873 4658);
FORCEPROP 2 LAST CDS_LIB mstr_standard
J 0
(-2875 4650);
PAINT MONO (-2875 4650);
DISPLAY INVISIBLE (-2875 4650);
FORCEPROP 1 LAST BODY_TYPE PLUMBING
J 2
(-2875 4600);
DISPLAY 1.595745 (-2875 4600);
PAINT GREEN (-2875 4600);
DISPLAY INVISIBLE (-2875 4600);
FORCEPROP 1 LAST HDL_TAP TRUE
J 2
(-3200 4525);
DISPLAY 1.595745 (-3200 4525);
PAINT GREEN (-3200 4525);
DISPLAY INVISIBLE (-3200 4525);
FORCEPROP 1 LAST PATH I170
J 2
(-2873 4650);
DISPLAY 0.872340 (-2873 4650);
PAINT GREEN (-2873 4650);
DISPLAY INVISIBLE (-2873 4650);
FORCEADD OFFPAGE..3
(-2025 4775);
FORCEPROP 2 LAST $XR0 43 
J 0
(-1811 4775);
DISPLAY 0.638298 (-1811 4775);
PAINT MONO (-1811 4775);
FORCEPROP 2 LAST $XR1 44 
J 0
(-1721 4775);
DISPLAY 0.638298 (-1721 4775);
PAINT MONO (-1721 4775);
FORCEPROP 2 LAST CDS_LIB mstr_standard
J 0
(-2025 4775);
PAINT MONO (-2025 4775);
DISPLAY INVISIBLE (-2025 4775);
FORCEPROP 1 LAST OFFPAGE TRUE
J 0
(-1700 4650);
DISPLAY 1.170213 (-1700 4650);
PAINT GREEN (-1700 4650);
DISPLAY INVISIBLE (-1700 4650);
FORCEPROP 1 LAST COMMENT_BODY TRUE
J 0
(-2075 4675);
DISPLAY 1.170213 (-2075 4675);
PAINT GREEN (-2075 4675);
DISPLAY INVISIBLE (-2075 4675);
FORCEPROP 2 LAST PATH I171
J 0
(-1825 4850);
DISPLAY 1.021277 (-1825 4850);
PAINT ORANGE (-1825 4850);
DISPLAY INVISIBLE (-1825 4850);
FORCEADD SKX_EXT_B..3
(-4200 2600);
FORCEPROP 1 LAST LOCATION U5D1
J 0
(-5000 4950);
DISPLAY 0.617021 (-5000 4950);
PAINT AQUA (-5000 4950);
FORCEPROP 1 LAST PART_NUMBER TBD
J 0
(-5000 350);
DISPLAY 0.617021 (-5000 350);
PAINT BLUE (-5000 350);
FORCEPROP 1 LAST MATERIAL IC
J 0
(-5000 4900);
DISPLAY 0.617021 (-5000 4900);
PAINT SKYBLUE (-5000 4900);
FORCEPROP 2 LASTPIN (-3350 550) $PN D53
J 0
(-3340 560);
DISPLAY 0.617021 (-3340 560);
PAINT ORANGE (-3340 560);
FORCEPROP 2 LASTPIN (-3350 1600) $PN G48
J 0
(-3340 1610);
DISPLAY 0.617021 (-3340 1610);
PAINT ORANGE (-3340 1610);
FORCEPROP 2 LASTPIN (-3350 1550) $PN G50
J 0
(-3340 1560);
DISPLAY 0.617021 (-3340 1560);
PAINT ORANGE (-3340 1560);
FORCEPROP 2 LASTPIN (-3350 1500) $PN C48
J 0
(-3340 1510);
DISPLAY 0.617021 (-3340 1510);
PAINT ORANGE (-3340 1510);
FORCEPROP 2 LASTPIN (-3350 1450) $PN C50
J 0
(-3340 1460);
DISPLAY 0.617021 (-3340 1460);
PAINT ORANGE (-3340 1460);
FORCEPROP 2 LASTPIN (-3350 2800) $PN K47
J 0
(-3340 2810);
DISPLAY 0.617021 (-3340 2810);
PAINT ORANGE (-3340 2810);
FORCEPROP 2 LASTPIN (-3350 2750) $PN D51
J 0
(-3340 2760);
DISPLAY 0.617021 (-3340 2760);
PAINT ORANGE (-3340 2760);
FORCEPROP 2 LASTPIN (-3350 2700) $PN K49
J 0
(-3340 2710);
DISPLAY 0.617021 (-3340 2710);
PAINT ORANGE (-3340 2710);
FORCEPROP 2 LASTPIN (-3350 2650) $PN F51
J 0
(-3340 2660);
DISPLAY 0.617021 (-3340 2660);
PAINT ORANGE (-3340 2660);
FORCEPROP 2 LASTPIN (-3350 2600) $PN J48
J 0
(-3340 2610);
DISPLAY 0.617021 (-3340 2610);
PAINT ORANGE (-3340 2610);
FORCEPROP 2 LASTPIN (-3350 2550) $PN J64
J 0
(-3340 2560);
DISPLAY 0.617021 (-3340 2560);
PAINT ORANGE (-3340 2560);
FORCEPROP 2 LASTPIN (-3350 2500) $PN G62
J 0
(-3340 2510);
DISPLAY 0.617021 (-3340 2510);
PAINT ORANGE (-3340 2510);
FORCEPROP 2 LASTPIN (-3350 2450) $PN J54
J 0
(-3340 2460);
DISPLAY 0.617021 (-3340 2460);
PAINT ORANGE (-3340 2460);
FORCEPROP 2 LASTPIN (-3350 2400) $PN F61
J 0
(-3340 2410);
DISPLAY 0.617021 (-3340 2410);
PAINT ORANGE (-3340 2410);
FORCEPROP 2 LASTPIN (-3350 2350) $PN C60
J 0
(-3340 2360);
DISPLAY 0.617021 (-3340 2360);
PAINT ORANGE (-3340 2360);
FORCEPROP 2 LASTPIN (-3350 2300) $PN G60
J 0
(-3340 2310);
DISPLAY 0.617021 (-3340 2310);
PAINT ORANGE (-3340 2310);
FORCEPROP 2 LASTPIN (-3350 2250) $PN D59
J 0
(-3340 2260);
DISPLAY 0.617021 (-3340 2260);
PAINT ORANGE (-3340 2260);
FORCEPROP 2 LASTPIN (-3350 2200) $PN F59
J 0
(-3340 2210);
DISPLAY 0.617021 (-3340 2210);
PAINT ORANGE (-3340 2210);
FORCEPROP 2 LASTPIN (-3350 2150) $PN G58
J 0
(-3340 2160);
DISPLAY 0.617021 (-3340 2160);
PAINT ORANGE (-3340 2160);
FORCEPROP 2 LASTPIN (-3350 2100) $PN C58
J 0
(-3340 2110);
DISPLAY 0.617021 (-3340 2110);
PAINT ORANGE (-3340 2110);
FORCEPROP 2 LASTPIN (-3350 2050) $PN D57
J 0
(-3340 2060);
DISPLAY 0.617021 (-3340 2060);
PAINT ORANGE (-3340 2060);
FORCEPROP 2 LASTPIN (-3350 2000) $PN F57
J 0
(-3340 2010);
DISPLAY 0.617021 (-3340 2010);
PAINT ORANGE (-3340 2010);
FORCEPROP 2 LASTPIN (-3350 1950) $PN F53
J 0
(-3340 1960);
DISPLAY 0.617021 (-3340 1960);
PAINT ORANGE (-3340 1960);
FORCEPROP 2 LASTPIN (-5050 1450) $PN AG66
J 2
(-5060 1460);
DISPLAY 0.617021 (-5060 1460);
PAINT ORANGE (-5060 1460);
FORCEPROP 2 LASTPIN (-5050 1400) $PN AC66
J 2
(-5060 1410);
DISPLAY 0.617021 (-5060 1410);
PAINT ORANGE (-5060 1410);
FORCEPROP 2 LASTPIN (-5050 1350) $PN AF69
J 2
(-5060 1360);
DISPLAY 0.617021 (-5060 1360);
PAINT ORANGE (-5060 1360);
FORCEPROP 2 LASTPIN (-5050 1300) $PN AD69
J 2
(-5060 1310);
DISPLAY 0.617021 (-5060 1310);
PAINT ORANGE (-5060 1310);
FORCEPROP 2 LASTPIN (-5050 1250) $PN AF65
J 2
(-5060 1260);
DISPLAY 0.617021 (-5060 1260);
PAINT ORANGE (-5060 1260);
FORCEPROP 2 LASTPIN (-5050 1200) $PN AD65
J 2
(-5060 1210);
DISPLAY 0.617021 (-5060 1210);
PAINT ORANGE (-5060 1210);
FORCEPROP 2 LASTPIN (-5050 1150) $PN AG68
J 2
(-5060 1160);
DISPLAY 0.617021 (-5060 1160);
PAINT ORANGE (-5060 1160);
FORCEPROP 2 LASTPIN (-5050 1100) $PN AC68
J 2
(-5060 1110);
DISPLAY 0.617021 (-5060 1110);
PAINT ORANGE (-5060 1110);
FORCEPROP 2 LASTPIN (-3350 4700) $PN AD67
J 0
(-3340 4710);
DISPLAY 0.617021 (-3340 4710);
PAINT ORANGE (-3340 4710);
FORCEPROP 2 LASTPIN (-3350 4650) $PN L24
J 0
(-3340 4660);
DISPLAY 0.617021 (-3340 4660);
PAINT ORANGE (-3340 4660);
FORCEPROP 2 LASTPIN (-3350 4600) $PN L30
J 0
(-3340 4610);
DISPLAY 0.617021 (-3340 4610);
PAINT ORANGE (-3340 4610);
FORCEPROP 2 LASTPIN (-3350 4550) $PN L36
J 0
(-3340 4560);
DISPLAY 0.617021 (-3340 4560);
PAINT ORANGE (-3340 4560);
FORCEPROP 2 LASTPIN (-3350 4500) $PN C40
J 0
(-3340 4510);
DISPLAY 0.617021 (-3340 4510);
PAINT ORANGE (-3340 4510);
FORCEPROP 2 LASTPIN (-3350 4450) $PN M75
J 0
(-3340 4460);
DISPLAY 0.617021 (-3340 4460);
PAINT ORANGE (-3340 4460);
FORCEPROP 2 LASTPIN (-3350 4400) $PN T81
J 0
(-3340 4410);
DISPLAY 0.617021 (-3340 4410);
PAINT ORANGE (-3340 4410);
FORCEPROP 2 LASTPIN (-3350 4350) $PN V85
J 0
(-3340 4360);
DISPLAY 0.617021 (-3340 4360);
PAINT ORANGE (-3340 4360);
FORCEPROP 2 LASTPIN (-3350 4300) $PN AM85
J 0
(-3340 4310);
DISPLAY 0.617021 (-3340 4310);
PAINT ORANGE (-3340 4310);
FORCEPROP 2 LASTPIN (-3350 4250) $PN AF67
J 0
(-3340 4260);
DISPLAY 0.617021 (-3340 4260);
PAINT ORANGE (-3340 4260);
FORCEPROP 2 LASTPIN (-3350 4200) $PN R24
J 0
(-3340 4210);
DISPLAY 0.617021 (-3340 4210);
PAINT ORANGE (-3340 4210);
FORCEPROP 2 LASTPIN (-3350 4150) $PN N30
J 0
(-3340 4160);
DISPLAY 0.617021 (-3340 4160);
PAINT ORANGE (-3340 4160);
FORCEPROP 2 LASTPIN (-3350 4100) $PN N36
J 0
(-3340 4110);
DISPLAY 0.617021 (-3340 4110);
PAINT ORANGE (-3340 4110);
FORCEPROP 2 LASTPIN (-3350 4050) $PN E40
J 0
(-3340 4060);
DISPLAY 0.617021 (-3340 4060);
PAINT ORANGE (-3340 4060);
FORCEPROP 2 LASTPIN (-3350 4000) $PN P75
J 0
(-3340 4010);
DISPLAY 0.617021 (-3340 4010);
PAINT ORANGE (-3340 4010);
FORCEPROP 2 LASTPIN (-3350 3950) $PN R80
J 0
(-3340 3960);
DISPLAY 0.617021 (-3340 3960);
PAINT ORANGE (-3340 3960);
FORCEPROP 2 LASTPIN (-3350 3900) $PN P85
J 0
(-3340 3910);
DISPLAY 0.617021 (-3340 3910);
PAINT ORANGE (-3340 3910);
FORCEPROP 2 LASTPIN (-3350 3850) $PN AH85
J 0
(-3340 3860);
DISPLAY 0.617021 (-3340 3860);
PAINT ORANGE (-3340 3860);
FORCEPROP 2 LASTPIN (-3350 3750) $PN AB67
J 0
(-3340 3760);
DISPLAY 0.617021 (-3340 3760);
PAINT ORANGE (-3340 3760);
FORCEPROP 2 LASTPIN (-3350 3700) $PN J24
J 0
(-3340 3710);
DISPLAY 0.617021 (-3340 3710);
PAINT ORANGE (-3340 3710);
FORCEPROP 2 LASTPIN (-3350 3650) $PN J30
J 0
(-3340 3660);
DISPLAY 0.617021 (-3340 3660);
PAINT ORANGE (-3340 3660);
FORCEPROP 2 LASTPIN (-3350 3600) $PN J36
J 0
(-3340 3610);
DISPLAY 0.617021 (-3340 3610);
PAINT ORANGE (-3340 3610);
FORCEPROP 2 LASTPIN (-3350 3550) $PN A40
J 0
(-3340 3560);
DISPLAY 0.617021 (-3340 3560);
PAINT ORANGE (-3340 3560);
FORCEPROP 2 LASTPIN (-3350 3500) $PN K75
J 0
(-3340 3510);
DISPLAY 0.617021 (-3340 3510);
PAINT ORANGE (-3340 3510);
FORCEPROP 2 LASTPIN (-3350 3450) $PN U82
J 0
(-3340 3460);
DISPLAY 0.617021 (-3340 3460);
PAINT ORANGE (-3340 3460);
FORCEPROP 2 LASTPIN (-3350 3400) $PN U84
J 0
(-3340 3410);
DISPLAY 0.617021 (-3340 3410);
PAINT ORANGE (-3340 3410);
FORCEPROP 2 LASTPIN (-3350 3350) $PN AL84
J 0
(-3340 3360);
DISPLAY 0.617021 (-3340 3360);
PAINT ORANGE (-3340 3360);
FORCEPROP 2 LASTPIN (-3350 3300) $PN AH67
J 0
(-3340 3310);
DISPLAY 0.617021 (-3340 3310);
PAINT ORANGE (-3340 3310);
FORCEPROP 2 LASTPIN (-3350 3250) $PN N24
J 0
(-3340 3260);
DISPLAY 0.617021 (-3340 3260);
PAINT ORANGE (-3340 3260);
FORCEPROP 2 LASTPIN (-3350 3200) $PN R30
J 0
(-3340 3210);
DISPLAY 0.617021 (-3340 3210);
PAINT ORANGE (-3340 3210);
FORCEPROP 2 LASTPIN (-3350 3150) $PN R36
J 0
(-3340 3160);
DISPLAY 0.617021 (-3340 3160);
PAINT ORANGE (-3340 3160);
FORCEPROP 2 LASTPIN (-3350 3100) $PN G40
J 0
(-3340 3110);
DISPLAY 0.617021 (-3340 3110);
PAINT ORANGE (-3340 3110);
FORCEPROP 2 LASTPIN (-3350 3050) $PN T75
J 0
(-3340 3060);
DISPLAY 0.617021 (-3340 3060);
PAINT ORANGE (-3340 3060);
FORCEPROP 2 LASTPIN (-3350 3000) $PN P79
J 0
(-3340 3010);
DISPLAY 0.617021 (-3340 3010);
PAINT ORANGE (-3340 3010);
FORCEPROP 2 LASTPIN (-3350 2950) $PN R84
J 0
(-3340 2960);
DISPLAY 0.617021 (-3340 2960);
PAINT ORANGE (-3340 2960);
FORCEPROP 2 LASTPIN (-3350 2900) $PN AJ84
J 0
(-3340 2910);
DISPLAY 0.617021 (-3340 2910);
PAINT ORANGE (-3340 2910);
FORCEPROP 2 LASTPIN (-5050 4700) $PN K23
J 2
(-5060 4710);
DISPLAY 0.617021 (-5060 4710);
PAINT ORANGE (-5060 4710);
FORCEPROP 2 LASTPIN (-5050 4650) $PN H23
J 2
(-5060 4660);
DISPLAY 0.617021 (-5060 4660);
PAINT ORANGE (-5060 4660);
FORCEPROP 2 LASTPIN (-5050 4600) $PN N26
J 2
(-5060 4610);
DISPLAY 0.617021 (-5060 4610);
PAINT ORANGE (-5060 4610);
FORCEPROP 2 LASTPIN (-5050 4550) $PN L26
J 2
(-5060 4560);
DISPLAY 0.617021 (-5060 4560);
PAINT ORANGE (-5060 4560);
FORCEPROP 2 LASTPIN (-5050 4500) $PN T23
J 2
(-5060 4510);
DISPLAY 0.617021 (-5060 4510);
PAINT ORANGE (-5060 4510);
FORCEPROP 2 LASTPIN (-5050 4450) $PN P23
J 2
(-5060 4460);
DISPLAY 0.617021 (-5060 4460);
PAINT ORANGE (-5060 4460);
FORCEPROP 2 LASTPIN (-5050 4400) $PN P25
J 2
(-5060 4410);
DISPLAY 0.617021 (-5060 4410);
PAINT ORANGE (-5060 4410);
FORCEPROP 2 LASTPIN (-5050 4350) $PN K25
J 2
(-5060 4360);
DISPLAY 0.617021 (-5060 4360);
PAINT ORANGE (-5060 4360);
FORCEPROP 2 LASTPIN (-5050 4300) $PN P29
J 2
(-5060 4310);
DISPLAY 0.617021 (-5060 4310);
PAINT ORANGE (-5060 4310);
FORCEPROP 2 LASTPIN (-5050 4250) $PN K29
J 2
(-5060 4260);
DISPLAY 0.617021 (-5060 4260);
PAINT ORANGE (-5060 4260);
FORCEPROP 2 LASTPIN (-5050 4200) $PN N32
J 2
(-5060 4210);
DISPLAY 0.617021 (-5060 4210);
PAINT ORANGE (-5060 4210);
FORCEPROP 2 LASTPIN (-5050 4150) $PN L32
J 2
(-5060 4160);
DISPLAY 0.617021 (-5060 4160);
PAINT ORANGE (-5060 4160);
FORCEPROP 2 LASTPIN (-5050 4100) $PN N28
J 2
(-5060 4110);
DISPLAY 0.617021 (-5060 4110);
PAINT ORANGE (-5060 4110);
FORCEPROP 2 LASTPIN (-5050 4050) $PN L28
J 2
(-5060 4060);
DISPLAY 0.617021 (-5060 4060);
PAINT ORANGE (-5060 4060);
FORCEPROP 2 LASTPIN (-5050 4000) $PN P31
J 2
(-5060 4010);
DISPLAY 0.617021 (-5060 4010);
PAINT ORANGE (-5060 4010);
FORCEPROP 2 LASTPIN (-5050 3950) $PN K31
J 2
(-5060 3960);
DISPLAY 0.617021 (-5060 3960);
PAINT ORANGE (-5060 3960);
FORCEPROP 2 LASTPIN (-5050 3900) $PN P35
J 2
(-5060 3910);
DISPLAY 0.617021 (-5060 3910);
PAINT ORANGE (-5060 3910);
FORCEPROP 2 LASTPIN (-5050 3850) $PN K35
J 2
(-5060 3860);
DISPLAY 0.617021 (-5060 3860);
PAINT ORANGE (-5060 3860);
FORCEPROP 2 LASTPIN (-5050 3800) $PN N38
J 2
(-5060 3810);
DISPLAY 0.617021 (-5060 3810);
PAINT ORANGE (-5060 3810);
FORCEPROP 2 LASTPIN (-5050 3750) $PN L38
J 2
(-5060 3760);
DISPLAY 0.617021 (-5060 3760);
PAINT ORANGE (-5060 3760);
FORCEPROP 2 LASTPIN (-5050 3700) $PN N34
J 2
(-5060 3710);
DISPLAY 0.617021 (-5060 3710);
PAINT ORANGE (-5060 3710);
FORCEPROP 2 LASTPIN (-5050 3650) $PN L34
J 2
(-5060 3660);
DISPLAY 0.617021 (-5060 3660);
PAINT ORANGE (-5060 3660);
FORCEPROP 2 LASTPIN (-5050 3600) $PN P37
J 2
(-5060 3610);
DISPLAY 0.617021 (-5060 3610);
PAINT ORANGE (-5060 3610);
FORCEPROP 2 LASTPIN (-5050 3550) $PN K37
J 2
(-5060 3560);
DISPLAY 0.617021 (-5060 3560);
PAINT ORANGE (-5060 3560);
FORCEPROP 2 LASTPIN (-5050 3500) $PN F39
J 2
(-5060 3510);
DISPLAY 0.617021 (-5060 3510);
PAINT ORANGE (-5060 3510);
FORCEPROP 2 LASTPIN (-5050 3450) $PN B39
J 2
(-5060 3460);
DISPLAY 0.617021 (-5060 3460);
PAINT ORANGE (-5060 3460);
FORCEPROP 2 LASTPIN (-5050 3400) $PN F41
J 2
(-5060 3410);
DISPLAY 0.617021 (-5060 3410);
PAINT ORANGE (-5060 3410);
FORCEPROP 2 LASTPIN (-5050 3350) $PN E42
J 2
(-5060 3360);
DISPLAY 0.617021 (-5060 3360);
PAINT ORANGE (-5060 3360);
FORCEPROP 2 LASTPIN (-5050 3300) $PN E38
J 2
(-5060 3310);
DISPLAY 0.617021 (-5060 3310);
PAINT ORANGE (-5060 3310);
FORCEPROP 2 LASTPIN (-5050 3250) $PN C38
J 2
(-5060 3260);
DISPLAY 0.617021 (-5060 3260);
PAINT ORANGE (-5060 3260);
FORCEPROP 2 LASTPIN (-5050 3200) $PN B41
J 2
(-5060 3210);
DISPLAY 0.617021 (-5060 3210);
PAINT ORANGE (-5060 3210);
FORCEPROP 2 LASTPIN (-5050 3150) $PN C42
J 2
(-5060 3160);
DISPLAY 0.617021 (-5060 3160);
PAINT ORANGE (-5060 3160);
FORCEPROP 2 LASTPIN (-5050 3100) $PN R74
J 2
(-5060 3110);
DISPLAY 0.617021 (-5060 3110);
PAINT ORANGE (-5060 3110);
FORCEPROP 2 LASTPIN (-5050 3050) $PN L74
J 2
(-5060 3060);
DISPLAY 0.617021 (-5060 3060);
PAINT ORANGE (-5060 3060);
FORCEPROP 2 LASTPIN (-5050 3000) $PN P77
J 2
(-5060 3010);
DISPLAY 0.617021 (-5060 3010);
PAINT ORANGE (-5060 3010);
FORCEPROP 2 LASTPIN (-5050 2950) $PN M77
J 2
(-5060 2960);
DISPLAY 0.617021 (-5060 2960);
PAINT ORANGE (-5060 2960);
FORCEPROP 2 LASTPIN (-5050 2900) $PN P73
J 2
(-5060 2910);
DISPLAY 0.617021 (-5060 2910);
PAINT ORANGE (-5060 2910);
FORCEPROP 2 LASTPIN (-5050 2850) $PN M73
J 2
(-5060 2860);
DISPLAY 0.617021 (-5060 2860);
PAINT ORANGE (-5060 2860);
FORCEPROP 2 LASTPIN (-5050 2800) $PN R76
J 2
(-5060 2810);
DISPLAY 0.617021 (-5060 2810);
PAINT ORANGE (-5060 2810);
FORCEPROP 2 LASTPIN (-5050 2750) $PN L76
J 2
(-5060 2760);
DISPLAY 0.617021 (-5060 2760);
PAINT ORANGE (-5060 2760);
FORCEPROP 2 LASTPIN (-5050 2700) $PN N80
J 2
(-5060 2710);
DISPLAY 0.617021 (-5060 2710);
PAINT ORANGE (-5060 2710);
FORCEPROP 2 LASTPIN (-5050 2650) $PN R82
J 2
(-5060 2660);
DISPLAY 0.617021 (-5060 2660);
PAINT ORANGE (-5060 2660);
FORCEPROP 2 LASTPIN (-5050 2600) $PN V79
J 2
(-5060 2610);
DISPLAY 0.617021 (-5060 2610);
PAINT ORANGE (-5060 2610);
FORCEPROP 2 LASTPIN (-5050 2550) $PN W80
J 2
(-5060 2560);
DISPLAY 0.617021 (-5060 2560);
PAINT ORANGE (-5060 2560);
FORCEPROP 2 LASTPIN (-5050 2500) $PN M81
J 2
(-5060 2510);
DISPLAY 0.617021 (-5060 2510);
PAINT ORANGE (-5060 2510);
FORCEPROP 2 LASTPIN (-5050 2450) $PN N82
J 2
(-5060 2460);
DISPLAY 0.617021 (-5060 2460);
PAINT ORANGE (-5060 2460);
FORCEPROP 2 LASTPIN (-5050 2400) $PN T79
J 2
(-5060 2410);
DISPLAY 0.617021 (-5060 2410);
PAINT ORANGE (-5060 2410);
FORCEPROP 2 LASTPIN (-5050 2350) $PN V81
J 2
(-5060 2360);
DISPLAY 0.617021 (-5060 2360);
PAINT ORANGE (-5060 2360);
FORCEPROP 2 LASTPIN (-5050 2300) $PN N84
J 2
(-5060 2310);
DISPLAY 0.617021 (-5060 2310);
PAINT ORANGE (-5060 2310);
FORCEPROP 2 LASTPIN (-5050 2250) $PN N86
J 2
(-5060 2260);
DISPLAY 0.617021 (-5060 2260);
PAINT ORANGE (-5060 2260);
FORCEPROP 2 LASTPIN (-5050 2200) $PN AA84
J 2
(-5060 2210);
DISPLAY 0.617021 (-5060 2210);
PAINT ORANGE (-5060 2210);
FORCEPROP 2 LASTPIN (-5050 2150) $PN AA86
J 2
(-5060 2160);
DISPLAY 0.617021 (-5060 2160);
PAINT ORANGE (-5060 2160);
FORCEPROP 2 LASTPIN (-5050 2100) $PN L84
J 2
(-5060 2110);
DISPLAY 0.617021 (-5060 2110);
PAINT ORANGE (-5060 2110);
FORCEPROP 2 LASTPIN (-5050 2050) $PN L86
J 2
(-5060 2060);
DISPLAY 0.617021 (-5060 2060);
PAINT ORANGE (-5060 2060);
FORCEPROP 2 LASTPIN (-5050 2000) $PN W84
J 2
(-5060 2010);
DISPLAY 0.617021 (-5060 2010);
PAINT ORANGE (-5060 2010);
FORCEPROP 2 LASTPIN (-5050 1950) $PN W86
J 2
(-5060 1960);
DISPLAY 0.617021 (-5060 1960);
PAINT ORANGE (-5060 1960);
FORCEPROP 2 LASTPIN (-5050 1900) $PN AG84
J 2
(-5060 1910);
DISPLAY 0.617021 (-5060 1910);
PAINT ORANGE (-5060 1910);
FORCEPROP 2 LASTPIN (-5050 1850) $PN AG86
J 2
(-5060 1860);
DISPLAY 0.617021 (-5060 1860);
PAINT ORANGE (-5060 1860);
FORCEPROP 2 LASTPIN (-5050 1800) $PN AR84
J 2
(-5060 1810);
DISPLAY 0.617021 (-5060 1810);
PAINT ORANGE (-5060 1810);
FORCEPROP 2 LASTPIN (-5050 1750) $PN AR86
J 2
(-5060 1760);
DISPLAY 0.617021 (-5060 1760);
PAINT ORANGE (-5060 1760);
FORCEPROP 2 LASTPIN (-5050 1700) $PN AE84
J 2
(-5060 1710);
DISPLAY 0.617021 (-5060 1710);
PAINT ORANGE (-5060 1710);
FORCEPROP 2 LASTPIN (-5050 1650) $PN AE86
J 2
(-5060 1660);
DISPLAY 0.617021 (-5060 1660);
PAINT ORANGE (-5060 1660);
FORCEPROP 2 LASTPIN (-5050 1600) $PN AN84
J 2
(-5060 1610);
DISPLAY 0.617021 (-5060 1610);
PAINT ORANGE (-5060 1610);
FORCEPROP 2 LASTPIN (-5050 1550) $PN AN86
J 2
(-5060 1560);
DISPLAY 0.617021 (-5060 1560);
PAINT ORANGE (-5060 1560);
FORCEPROP 2 LASTPIN (-3350 1350) $PN K45
J 0
(-3340 1360);
DISPLAY 0.617021 (-3340 1360);
PAINT ORANGE (-3340 1360);
FORCEPROP 2 LASTPIN (-3350 1300) $PN F45
J 0
(-3340 1310);
DISPLAY 0.617021 (-3340 1310);
PAINT ORANGE (-3340 1310);
FORCEPROP 2 LASTPIN (-3350 1250) $PN D49
J 0
(-3340 1260);
DISPLAY 0.617021 (-3340 1260);
PAINT ORANGE (-3340 1260);
FORCEPROP 2 LASTPIN (-3350 1200) $PN B51
J 0
(-3340 1210);
DISPLAY 0.617021 (-3340 1210);
PAINT ORANGE (-3340 1210);
FORCEPROP 2 LASTPIN (-3350 1150) $PN F47
J 0
(-3340 1160);
DISPLAY 0.617021 (-3340 1160);
PAINT ORANGE (-3340 1160);
FORCEPROP 2 LASTPIN (-3350 1100) $PN D47
J 0
(-3340 1110);
DISPLAY 0.617021 (-3340 1110);
PAINT ORANGE (-3340 1110);
FORCEPROP 2 LASTPIN (-3350 1050) $PN F49
J 0
(-3340 1060);
DISPLAY 0.617021 (-3340 1060);
PAINT ORANGE (-3340 1060);
FORCEPROP 2 LASTPIN (-3350 1000) $PN G52
J 0
(-3340 1010);
DISPLAY 0.617021 (-3340 1010);
PAINT ORANGE (-3340 1010);
FORCEPROP 2 LASTPIN (-5050 1000) $PN B57
J 2
(-5060 1010);
DISPLAY 0.617021 (-5060 1010);
PAINT ORANGE (-5060 1010);
FORCEPROP 2 LASTPIN (-5050 950) $PN G56
J 2
(-5060 960);
DISPLAY 0.617021 (-5060 960);
PAINT ORANGE (-5060 960);
FORCEPROP 2 LASTPIN (-5050 900) $PN B55
J 2
(-5060 910);
DISPLAY 0.617021 (-5060 910);
PAINT ORANGE (-5060 910);
FORCEPROP 2 LASTPIN (-5050 850) $PN D55
J 2
(-5060 860);
DISPLAY 0.617021 (-5060 860);
PAINT ORANGE (-5060 860);
FORCEPROP 2 LASTPIN (-5050 800) $PN C56
J 2
(-5060 810);
DISPLAY 0.617021 (-5060 810);
PAINT ORANGE (-5060 810);
FORCEPROP 2 LASTPIN (-5050 750) $PN J56
J 2
(-5060 760);
DISPLAY 0.617021 (-5060 760);
PAINT ORANGE (-5060 760);
FORCEPROP 2 LASTPIN (-5050 700) $PN C54
J 2
(-5060 710);
DISPLAY 0.617021 (-5060 710);
PAINT ORANGE (-5060 710);
FORCEPROP 2 LASTPIN (-5050 650) $PN F55
J 2
(-5060 660);
DISPLAY 0.617021 (-5060 660);
PAINT ORANGE (-5060 660);
FORCEPROP 2 LASTPIN (-3350 1850) $PN D63
J 0
(-3340 1860);
DISPLAY 0.617021 (-3340 1860);
PAINT ORANGE (-3340 1860);
FORCEPROP 2 LASTPIN (-3350 1800) $PN B63
J 0
(-3340 1810);
DISPLAY 0.617021 (-3340 1810);
PAINT ORANGE (-3340 1810);
FORCEPROP 2 LASTPIN (-3350 1750) $PN C64
J 0
(-3340 1760);
DISPLAY 0.617021 (-3340 1760);
PAINT ORANGE (-3340 1760);
FORCEPROP 2 LASTPIN (-3350 1700) $PN C62
J 0
(-3340 1710);
DISPLAY 0.617021 (-3340 1710);
PAINT ORANGE (-3340 1710);
FORCEPROP 2 LASTPIN (-5050 550) $PN G46
J 2
(-5060 560);
DISPLAY 0.617021 (-5060 560);
PAINT ORANGE (-5060 560);
FORCEPROP 2 LASTPIN (-3350 900) $PN F63
J 0
(-3340 910);
DISPLAY 0.617021 (-3340 910);
PAINT ORANGE (-3340 910);
FORCEPROP 2 LASTPIN (-3350 850) $PN D61
J 0
(-3340 860);
DISPLAY 0.617021 (-3340 860);
PAINT ORANGE (-3340 860);
FORCEPROP 2 LASTPIN (-3350 800) $PN G54
J 0
(-3340 810);
DISPLAY 0.617021 (-3340 810);
PAINT ORANGE (-3340 810);
FORCEPROP 2 LASTPIN (-3350 750) $PN C52
J 0
(-3340 760);
DISPLAY 0.617021 (-3340 760);
PAINT ORANGE (-3340 760);
FORCEPROP 2 LASTPIN (-3350 600) $PN B61
J 0
(-3340 610);
DISPLAY 0.617021 (-3340 610);
PAINT ORANGE (-3340 610);
FORCEPROP 2 LASTPIN (-3350 650) $PN J60
J 0
(-3340 660);
DISPLAY 0.617021 (-3340 660);
PAINT ORANGE (-3340 660);
FORCEPROP 1 LAST PACK_TYPE BGA1
J 0
(-5000 5000);
PAINT SKYBLUE (-5000 5000);
DISPLAY INVISIBLE (-5000 5000);
FORCEPROP 2 LAST CDS_LIB chpset_lib
J 0
(-4200 2600);
PAINT ORANGE (-4200 2600);
DISPLAY INVISIBLE (-4200 2600);
FORCEPROP 2 LAST SEC_TYPE BGA1
J 0
(-5000 5000);
DISPLAY 1.021277 (-5000 5000);
PAINT ORANGE (-5000 5000);
DISPLAY INVISIBLE (-5000 5000);
FORCEPROP 2 LAST SEC 3
J 0
(-5000 5000);
DISPLAY 0.680851 (-5000 5000);
PAINT MONO (-5000 5000);
DISPLAY INVISIBLE (-5000 5000);
FORCEPROP 2 LAST CDS_LOCATION U5D1
J 0
(-5000 4950);
DISPLAY 0.617021 (-5000 4950);
PAINT AQUA (-5000 4950);
DISPLAY INVISIBLE (-5000 4950);
FORCEPROP 1 LAST PATH I172
J 0
(-4200 4900);
PAINT GREEN (-4200 4900);
DISPLAY INVISIBLE (-4200 4900);
FORCEPROP 0 LAST ROOM CPU0
J 0
(-5000 5050);
DISPLAY 1.021277 (-5000 5050);
PAINT ORANGE (-5000 5050);
DISPLAY INVISIBLE (-5000 5050);
FORCEADD TAP..6
(-5600 1350);
FORCEPROP 3 LASTPIN (-5550 1350) SIG_NAME M_A_ECC<5>
J 0
(-5540 1360);
DISPLAY 0.659574 (-5540 1360);
PAINT MONO (-5540 1360);
DISPLAY INVISIBLE (-5540 1360);
FORCEPROP 1 LASTPIN (-5550 1350) BN 5
J 0
(-5602 1358);
DISPLAY 0.617021 (-5602 1358);
PAINT PINK (-5602 1358);
FORCEPROP 2 LAST CDS_LIB mstr_standard
J 0
(-5600 1350);
PAINT MONO (-5600 1350);
DISPLAY INVISIBLE (-5600 1350);
FORCEPROP 1 LAST BODY_TYPE PLUMBING
J 0
(-5600 1300);
DISPLAY 1.595745 (-5600 1300);
PAINT GREEN (-5600 1300);
DISPLAY INVISIBLE (-5600 1300);
FORCEPROP 1 LAST HDL_TAP TRUE
J 0
(-5275 1225);
DISPLAY 1.595745 (-5275 1225);
PAINT GREEN (-5275 1225);
DISPLAY INVISIBLE (-5275 1225);
FORCEPROP 1 LAST PATH I18
J 0
(-5602 1350);
DISPLAY 0.872340 (-5602 1350);
PAINT GREEN (-5602 1350);
DISPLAY INVISIBLE (-5602 1350);
FORCEADD TAP..6
(-5600 1400);
FORCEPROP 3 LASTPIN (-5550 1400) SIG_NAME M_A_ECC<6>
J 0
(-5540 1410);
DISPLAY 0.659574 (-5540 1410);
PAINT MONO (-5540 1410);
DISPLAY INVISIBLE (-5540 1410);
FORCEPROP 1 LASTPIN (-5550 1400) BN 6
J 0
(-5602 1408);
DISPLAY 0.617021 (-5602 1408);
PAINT PINK (-5602 1408);
FORCEPROP 2 LAST CDS_LIB mstr_standard
J 0
(-5600 1400);
PAINT MONO (-5600 1400);
DISPLAY INVISIBLE (-5600 1400);
FORCEPROP 1 LAST BODY_TYPE PLUMBING
J 0
(-5600 1350);
DISPLAY 1.595745 (-5600 1350);
PAINT GREEN (-5600 1350);
DISPLAY INVISIBLE (-5600 1350);
FORCEPROP 1 LAST HDL_TAP TRUE
J 0
(-5275 1275);
DISPLAY 1.595745 (-5275 1275);
PAINT GREEN (-5275 1275);
DISPLAY INVISIBLE (-5275 1275);
FORCEPROP 1 LAST PATH I19
J 0
(-5602 1400);
DISPLAY 0.872340 (-5602 1400);
PAINT GREEN (-5602 1400);
DISPLAY INVISIBLE (-5602 1400);
FORCEADD OFFPAGE..5
(-6450 1050);
FORCEPROP 2 LAST $XR0 43 
J 0
(-6674 1050);
DISPLAY 0.638298 (-6674 1050);
PAINT MONO (-6674 1050);
FORCEPROP 2 LAST $XR1 44 
J 0
(-6764 1050);
DISPLAY 0.638298 (-6764 1050);
PAINT MONO (-6764 1050);
FORCEPROP 2 LAST CDS_LIB mstr_standard
J 0
(-6450 1050);
PAINT MONO (-6450 1050);
DISPLAY INVISIBLE (-6450 1050);
FORCEPROP 1 LAST OFFPAGE TRUE
J 0
(-6125 925);
DISPLAY 1.170213 (-6125 925);
PAINT GREEN (-6125 925);
DISPLAY INVISIBLE (-6125 925);
FORCEPROP 1 LAST COMMENT_BODY TRUE
J 0
(-6350 975);
DISPLAY 1.170213 (-6350 975);
PAINT GREEN (-6350 975);
DISPLAY INVISIBLE (-6350 975);
FORCEPROP 2 LAST PATH I2
J 0
(-6400 1125);
DISPLAY 1.021277 (-6400 1125);
PAINT ORANGE (-6400 1125);
DISPLAY INVISIBLE (-6400 1125);
FORCEADD TAP..6
(-5600 1450);
FORCEPROP 3 LASTPIN (-5550 1450) SIG_NAME M_A_ECC<7>
J 0
(-5540 1460);
DISPLAY 0.659574 (-5540 1460);
PAINT MONO (-5540 1460);
DISPLAY INVISIBLE (-5540 1460);
FORCEPROP 1 LASTPIN (-5550 1450) BN 7
J 0
(-5602 1458);
DISPLAY 0.617021 (-5602 1458);
PAINT PINK (-5602 1458);
FORCEPROP 2 LAST CDS_LIB mstr_standard
J 0
(-5600 1450);
PAINT MONO (-5600 1450);
DISPLAY INVISIBLE (-5600 1450);
FORCEPROP 1 LAST BODY_TYPE PLUMBING
J 0
(-5600 1400);
DISPLAY 1.595745 (-5600 1400);
PAINT GREEN (-5600 1400);
DISPLAY INVISIBLE (-5600 1400);
FORCEPROP 1 LAST HDL_TAP TRUE
J 0
(-5275 1325);
DISPLAY 1.595745 (-5275 1325);
PAINT GREEN (-5275 1325);
DISPLAY INVISIBLE (-5275 1325);
FORCEPROP 1 LAST PATH I20
J 0
(-5602 1450);
DISPLAY 0.872340 (-5602 1450);
PAINT GREEN (-5602 1450);
DISPLAY INVISIBLE (-5602 1450);
FORCEADD TAP..6
(-5600 1600);
FORCEPROP 3 LASTPIN (-5550 1600) SIG_NAME M_A_DQ<1>
J 0
(-5540 1610);
DISPLAY 0.659574 (-5540 1610);
PAINT MONO (-5540 1610);
DISPLAY INVISIBLE (-5540 1610);
FORCEPROP 1 LASTPIN (-5550 1600) BN 1
J 0
(-5602 1608);
DISPLAY 0.617021 (-5602 1608);
PAINT PINK (-5602 1608);
FORCEPROP 2 LAST CDS_LIB mstr_standard
J 0
(-5600 1600);
PAINT MONO (-5600 1600);
DISPLAY INVISIBLE (-5600 1600);
FORCEPROP 1 LAST BODY_TYPE PLUMBING
J 0
(-5600 1550);
DISPLAY 1.595745 (-5600 1550);
PAINT GREEN (-5600 1550);
DISPLAY INVISIBLE (-5600 1550);
FORCEPROP 1 LAST HDL_TAP TRUE
J 0
(-5275 1475);
DISPLAY 1.595745 (-5275 1475);
PAINT GREEN (-5275 1475);
DISPLAY INVISIBLE (-5275 1475);
FORCEPROP 1 LAST PATH I21
J 0
(-5602 1600);
DISPLAY 0.872340 (-5602 1600);
PAINT GREEN (-5602 1600);
DISPLAY INVISIBLE (-5602 1600);
FORCEADD TAP..6
(-5600 1550);
FORCEPROP 3 LASTPIN (-5550 1550) SIG_NAME M_A_DQ<0>
J 0
(-5540 1560);
DISPLAY 0.659574 (-5540 1560);
PAINT MONO (-5540 1560);
DISPLAY INVISIBLE (-5540 1560);
FORCEPROP 1 LASTPIN (-5550 1550) BN 0
J 0
(-5602 1558);
DISPLAY 0.617021 (-5602 1558);
PAINT PINK (-5602 1558);
FORCEPROP 2 LAST CDS_LIB mstr_standard
J 0
(-5600 1550);
PAINT MONO (-5600 1550);
DISPLAY INVISIBLE (-5600 1550);
FORCEPROP 1 LAST BODY_TYPE PLUMBING
J 0
(-5600 1500);
DISPLAY 1.595745 (-5600 1500);
PAINT GREEN (-5600 1500);
DISPLAY INVISIBLE (-5600 1500);
FORCEPROP 1 LAST HDL_TAP TRUE
J 0
(-5275 1425);
DISPLAY 1.595745 (-5275 1425);
PAINT GREEN (-5275 1425);
DISPLAY INVISIBLE (-5275 1425);
FORCEPROP 1 LAST PATH I22
J 0
(-5602 1550);
DISPLAY 0.872340 (-5602 1550);
PAINT GREEN (-5602 1550);
DISPLAY INVISIBLE (-5602 1550);
FORCEADD TAP..6
(-5600 1650);
FORCEPROP 3 LASTPIN (-5550 1650) SIG_NAME M_A_DQ<2>
J 0
(-5540 1660);
DISPLAY 0.659574 (-5540 1660);
PAINT MONO (-5540 1660);
DISPLAY INVISIBLE (-5540 1660);
FORCEPROP 1 LASTPIN (-5550 1650) BN 2
J 0
(-5602 1658);
DISPLAY 0.617021 (-5602 1658);
PAINT PINK (-5602 1658);
FORCEPROP 2 LAST CDS_LIB mstr_standard
J 0
(-5600 1650);
PAINT MONO (-5600 1650);
DISPLAY INVISIBLE (-5600 1650);
FORCEPROP 1 LAST BODY_TYPE PLUMBING
J 0
(-5600 1600);
DISPLAY 1.595745 (-5600 1600);
PAINT GREEN (-5600 1600);
DISPLAY INVISIBLE (-5600 1600);
FORCEPROP 1 LAST HDL_TAP TRUE
J 0
(-5275 1525);
DISPLAY 1.595745 (-5275 1525);
PAINT GREEN (-5275 1525);
DISPLAY INVISIBLE (-5275 1525);
FORCEPROP 1 LAST PATH I23
J 0
(-5602 1650);
DISPLAY 0.872340 (-5602 1650);
PAINT GREEN (-5602 1650);
DISPLAY INVISIBLE (-5602 1650);
FORCEADD TAP..6
(-5600 1700);
FORCEPROP 3 LASTPIN (-5550 1700) SIG_NAME M_A_DQ<3>
J 0
(-5540 1710);
DISPLAY 0.659574 (-5540 1710);
PAINT MONO (-5540 1710);
DISPLAY INVISIBLE (-5540 1710);
FORCEPROP 1 LASTPIN (-5550 1700) BN 3
J 0
(-5602 1708);
DISPLAY 0.617021 (-5602 1708);
PAINT PINK (-5602 1708);
FORCEPROP 2 LAST CDS_LIB mstr_standard
J 0
(-5600 1700);
PAINT MONO (-5600 1700);
DISPLAY INVISIBLE (-5600 1700);
FORCEPROP 1 LAST BODY_TYPE PLUMBING
J 0
(-5600 1650);
DISPLAY 1.595745 (-5600 1650);
PAINT GREEN (-5600 1650);
DISPLAY INVISIBLE (-5600 1650);
FORCEPROP 1 LAST HDL_TAP TRUE
J 0
(-5275 1575);
DISPLAY 1.595745 (-5275 1575);
PAINT GREEN (-5275 1575);
DISPLAY INVISIBLE (-5275 1575);
FORCEPROP 1 LAST PATH I24
J 0
(-5602 1700);
DISPLAY 0.872340 (-5602 1700);
PAINT GREEN (-5602 1700);
DISPLAY INVISIBLE (-5602 1700);
FORCEADD TAP..6
(-5600 1750);
FORCEPROP 3 LASTPIN (-5550 1750) SIG_NAME M_A_DQ<4>
J 0
(-5540 1760);
DISPLAY 0.659574 (-5540 1760);
PAINT MONO (-5540 1760);
DISPLAY INVISIBLE (-5540 1760);
FORCEPROP 1 LASTPIN (-5550 1750) BN 4
J 0
(-5602 1758);
DISPLAY 0.617021 (-5602 1758);
PAINT PINK (-5602 1758);
FORCEPROP 2 LAST CDS_LIB mstr_standard
J 0
(-5600 1750);
PAINT MONO (-5600 1750);
DISPLAY INVISIBLE (-5600 1750);
FORCEPROP 1 LAST BODY_TYPE PLUMBING
J 0
(-5600 1700);
DISPLAY 1.595745 (-5600 1700);
PAINT GREEN (-5600 1700);
DISPLAY INVISIBLE (-5600 1700);
FORCEPROP 1 LAST HDL_TAP TRUE
J 0
(-5275 1625);
DISPLAY 1.595745 (-5275 1625);
PAINT GREEN (-5275 1625);
DISPLAY INVISIBLE (-5275 1625);
FORCEPROP 1 LAST PATH I25
J 0
(-5602 1750);
DISPLAY 0.872340 (-5602 1750);
PAINT GREEN (-5602 1750);
DISPLAY INVISIBLE (-5602 1750);
FORCEADD TAP..6
(-5600 1800);
FORCEPROP 3 LASTPIN (-5550 1800) SIG_NAME M_A_DQ<5>
J 0
(-5540 1810);
DISPLAY 0.659574 (-5540 1810);
PAINT MONO (-5540 1810);
DISPLAY INVISIBLE (-5540 1810);
FORCEPROP 1 LASTPIN (-5550 1800) BN 5
J 0
(-5602 1808);
DISPLAY 0.617021 (-5602 1808);
PAINT PINK (-5602 1808);
FORCEPROP 2 LAST CDS_LIB mstr_standard
J 0
(-5600 1800);
PAINT MONO (-5600 1800);
DISPLAY INVISIBLE (-5600 1800);
FORCEPROP 1 LAST BODY_TYPE PLUMBING
J 0
(-5600 1750);
DISPLAY 1.595745 (-5600 1750);
PAINT GREEN (-5600 1750);
DISPLAY INVISIBLE (-5600 1750);
FORCEPROP 1 LAST HDL_TAP TRUE
J 0
(-5275 1675);
DISPLAY 1.595745 (-5275 1675);
PAINT GREEN (-5275 1675);
DISPLAY INVISIBLE (-5275 1675);
FORCEPROP 1 LAST PATH I26
J 0
(-5602 1800);
DISPLAY 0.872340 (-5602 1800);
PAINT GREEN (-5602 1800);
DISPLAY INVISIBLE (-5602 1800);
FORCEADD TAP..6
(-5600 1850);
FORCEPROP 3 LASTPIN (-5550 1850) SIG_NAME M_A_DQ<6>
J 0
(-5540 1860);
DISPLAY 0.659574 (-5540 1860);
PAINT MONO (-5540 1860);
DISPLAY INVISIBLE (-5540 1860);
FORCEPROP 1 LASTPIN (-5550 1850) BN 6
J 0
(-5602 1858);
DISPLAY 0.617021 (-5602 1858);
PAINT PINK (-5602 1858);
FORCEPROP 2 LAST CDS_LIB mstr_standard
J 0
(-5600 1850);
PAINT MONO (-5600 1850);
DISPLAY INVISIBLE (-5600 1850);
FORCEPROP 1 LAST BODY_TYPE PLUMBING
J 0
(-5600 1800);
DISPLAY 1.595745 (-5600 1800);
PAINT GREEN (-5600 1800);
DISPLAY INVISIBLE (-5600 1800);
FORCEPROP 1 LAST HDL_TAP TRUE
J 0
(-5275 1725);
DISPLAY 1.595745 (-5275 1725);
PAINT GREEN (-5275 1725);
DISPLAY INVISIBLE (-5275 1725);
FORCEPROP 1 LAST PATH I27
J 0
(-5602 1850);
DISPLAY 0.872340 (-5602 1850);
PAINT GREEN (-5602 1850);
DISPLAY INVISIBLE (-5602 1850);
FORCEADD TAP..6
(-5600 1950);
FORCEPROP 3 LASTPIN (-5550 1950) SIG_NAME M_A_DQ<8>
J 0
(-5540 1960);
DISPLAY 0.659574 (-5540 1960);
PAINT MONO (-5540 1960);
DISPLAY INVISIBLE (-5540 1960);
FORCEPROP 1 LASTPIN (-5550 1950) BN 8
J 0
(-5602 1958);
DISPLAY 0.617021 (-5602 1958);
PAINT PINK (-5602 1958);
FORCEPROP 2 LAST CDS_LIB mstr_standard
J 0
(-5600 1950);
PAINT MONO (-5600 1950);
DISPLAY INVISIBLE (-5600 1950);
FORCEPROP 1 LAST BODY_TYPE PLUMBING
J 0
(-5600 1900);
DISPLAY 1.595745 (-5600 1900);
PAINT GREEN (-5600 1900);
DISPLAY INVISIBLE (-5600 1900);
FORCEPROP 1 LAST HDL_TAP TRUE
J 0
(-5275 1825);
DISPLAY 1.595745 (-5275 1825);
PAINT GREEN (-5275 1825);
DISPLAY INVISIBLE (-5275 1825);
FORCEPROP 1 LAST PATH I28
J 0
(-5602 1950);
DISPLAY 0.872340 (-5602 1950);
PAINT GREEN (-5602 1950);
DISPLAY INVISIBLE (-5602 1950);
FORCEADD TAP..6
(-5600 1900);
FORCEPROP 3 LASTPIN (-5550 1900) SIG_NAME M_A_DQ<7>
J 0
(-5540 1910);
DISPLAY 0.659574 (-5540 1910);
PAINT MONO (-5540 1910);
DISPLAY INVISIBLE (-5540 1910);
FORCEPROP 1 LASTPIN (-5550 1900) BN 7
J 0
(-5602 1908);
DISPLAY 0.617021 (-5602 1908);
PAINT PINK (-5602 1908);
FORCEPROP 2 LAST CDS_LIB mstr_standard
J 0
(-5600 1900);
PAINT MONO (-5600 1900);
DISPLAY INVISIBLE (-5600 1900);
FORCEPROP 1 LAST BODY_TYPE PLUMBING
J 0
(-5600 1850);
DISPLAY 1.595745 (-5600 1850);
PAINT GREEN (-5600 1850);
DISPLAY INVISIBLE (-5600 1850);
FORCEPROP 1 LAST HDL_TAP TRUE
J 0
(-5275 1775);
DISPLAY 1.595745 (-5275 1775);
PAINT GREEN (-5275 1775);
DISPLAY INVISIBLE (-5275 1775);
FORCEPROP 1 LAST PATH I29
J 0
(-5602 1900);
DISPLAY 0.872340 (-5602 1900);
PAINT GREEN (-5602 1900);
DISPLAY INVISIBLE (-5602 1900);
FORCEADD OFFPAGE..5
(-6450 850);
FORCEPROP 2 LAST $XR0 43 
J 0
(-6674 850);
DISPLAY 0.638298 (-6674 850);
PAINT MONO (-6674 850);
FORCEPROP 2 LAST $XR1 44 
J 0
(-6764 850);
DISPLAY 0.638298 (-6764 850);
PAINT MONO (-6764 850);
FORCEPROP 2 LAST CDS_LIB mstr_standard
J 0
(-6450 850);
PAINT MONO (-6450 850);
DISPLAY INVISIBLE (-6450 850);
FORCEPROP 1 LAST OFFPAGE TRUE
J 0
(-6125 725);
DISPLAY 1.170213 (-6125 725);
PAINT GREEN (-6125 725);
DISPLAY INVISIBLE (-6125 725);
FORCEPROP 1 LAST COMMENT_BODY TRUE
J 0
(-6350 775);
DISPLAY 1.170213 (-6350 775);
PAINT GREEN (-6350 775);
DISPLAY INVISIBLE (-6350 775);
FORCEPROP 2 LAST PATH I3
J 0
(-6400 925);
DISPLAY 1.021277 (-6400 925);
PAINT ORANGE (-6400 925);
DISPLAY INVISIBLE (-6400 925);
FORCEADD TAP..6
(-5600 2000);
FORCEPROP 3 LASTPIN (-5550 2000) SIG_NAME M_A_DQ<9>
J 0
(-5540 2010);
DISPLAY 0.659574 (-5540 2010);
PAINT MONO (-5540 2010);
DISPLAY INVISIBLE (-5540 2010);
FORCEPROP 1 LASTPIN (-5550 2000) BN 9
J 0
(-5602 2008);
DISPLAY 0.617021 (-5602 2008);
PAINT PINK (-5602 2008);
FORCEPROP 2 LAST CDS_LIB mstr_standard
J 0
(-5600 2000);
PAINT MONO (-5600 2000);
DISPLAY INVISIBLE (-5600 2000);
FORCEPROP 1 LAST BODY_TYPE PLUMBING
J 0
(-5600 1950);
DISPLAY 1.595745 (-5600 1950);
PAINT GREEN (-5600 1950);
DISPLAY INVISIBLE (-5600 1950);
FORCEPROP 1 LAST HDL_TAP TRUE
J 0
(-5275 1875);
DISPLAY 1.595745 (-5275 1875);
PAINT GREEN (-5275 1875);
DISPLAY INVISIBLE (-5275 1875);
FORCEPROP 1 LAST PATH I31
J 0
(-5602 2000);
DISPLAY 0.872340 (-5602 2000);
PAINT GREEN (-5602 2000);
DISPLAY INVISIBLE (-5602 2000);
FORCEADD TAP..6
(-5600 2050);
FORCEPROP 3 LASTPIN (-5550 2050) SIG_NAME M_A_DQ<10>
J 0
(-5540 2060);
DISPLAY 0.659574 (-5540 2060);
PAINT MONO (-5540 2060);
DISPLAY INVISIBLE (-5540 2060);
FORCEPROP 1 LASTPIN (-5550 2050) BN 10
J 0
(-5602 2058);
DISPLAY 0.617021 (-5602 2058);
PAINT PINK (-5602 2058);
FORCEPROP 2 LAST CDS_LIB mstr_standard
J 0
(-5600 2050);
PAINT MONO (-5600 2050);
DISPLAY INVISIBLE (-5600 2050);
FORCEPROP 1 LAST BODY_TYPE PLUMBING
J 0
(-5600 2000);
DISPLAY 1.595745 (-5600 2000);
PAINT GREEN (-5600 2000);
DISPLAY INVISIBLE (-5600 2000);
FORCEPROP 1 LAST HDL_TAP TRUE
J 0
(-5275 1925);
DISPLAY 1.595745 (-5275 1925);
PAINT GREEN (-5275 1925);
DISPLAY INVISIBLE (-5275 1925);
FORCEPROP 1 LAST PATH I32
J 0
(-5602 2050);
DISPLAY 0.872340 (-5602 2050);
PAINT GREEN (-5602 2050);
DISPLAY INVISIBLE (-5602 2050);
FORCEADD TAP..6
(-5600 2100);
FORCEPROP 3 LASTPIN (-5550 2100) SIG_NAME M_A_DQ<11>
J 0
(-5540 2110);
DISPLAY 0.659574 (-5540 2110);
PAINT MONO (-5540 2110);
DISPLAY INVISIBLE (-5540 2110);
FORCEPROP 1 LASTPIN (-5550 2100) BN 11
J 0
(-5602 2108);
DISPLAY 0.617021 (-5602 2108);
PAINT PINK (-5602 2108);
FORCEPROP 2 LAST CDS_LIB mstr_standard
J 0
(-5600 2100);
PAINT MONO (-5600 2100);
DISPLAY INVISIBLE (-5600 2100);
FORCEPROP 1 LAST BODY_TYPE PLUMBING
J 0
(-5600 2050);
DISPLAY 1.595745 (-5600 2050);
PAINT GREEN (-5600 2050);
DISPLAY INVISIBLE (-5600 2050);
FORCEPROP 1 LAST HDL_TAP TRUE
J 0
(-5275 1975);
DISPLAY 1.595745 (-5275 1975);
PAINT GREEN (-5275 1975);
DISPLAY INVISIBLE (-5275 1975);
FORCEPROP 1 LAST PATH I33
J 0
(-5602 2100);
DISPLAY 0.872340 (-5602 2100);
PAINT GREEN (-5602 2100);
DISPLAY INVISIBLE (-5602 2100);
FORCEADD TAP..6
(-5600 2150);
FORCEPROP 3 LASTPIN (-5550 2150) SIG_NAME M_A_DQ<12>
J 0
(-5540 2160);
DISPLAY 0.659574 (-5540 2160);
PAINT MONO (-5540 2160);
DISPLAY INVISIBLE (-5540 2160);
FORCEPROP 1 LASTPIN (-5550 2150) BN 12
J 0
(-5602 2158);
DISPLAY 0.617021 (-5602 2158);
PAINT PINK (-5602 2158);
FORCEPROP 2 LAST CDS_LIB mstr_standard
J 0
(-5600 2150);
PAINT MONO (-5600 2150);
DISPLAY INVISIBLE (-5600 2150);
FORCEPROP 1 LAST BODY_TYPE PLUMBING
J 0
(-5600 2100);
DISPLAY 1.595745 (-5600 2100);
PAINT GREEN (-5600 2100);
DISPLAY INVISIBLE (-5600 2100);
FORCEPROP 1 LAST HDL_TAP TRUE
J 0
(-5275 2025);
DISPLAY 1.595745 (-5275 2025);
PAINT GREEN (-5275 2025);
DISPLAY INVISIBLE (-5275 2025);
FORCEPROP 1 LAST PATH I34
J 0
(-5602 2150);
DISPLAY 0.872340 (-5602 2150);
PAINT GREEN (-5602 2150);
DISPLAY INVISIBLE (-5602 2150);
FORCEADD TAP..6
(-5600 2200);
FORCEPROP 3 LASTPIN (-5550 2200) SIG_NAME M_A_DQ<13>
J 0
(-5540 2210);
DISPLAY 0.659574 (-5540 2210);
PAINT MONO (-5540 2210);
DISPLAY INVISIBLE (-5540 2210);
FORCEPROP 1 LASTPIN (-5550 2200) BN 13
J 0
(-5602 2208);
DISPLAY 0.617021 (-5602 2208);
PAINT PINK (-5602 2208);
FORCEPROP 2 LAST CDS_LIB mstr_standard
J 0
(-5600 2200);
PAINT MONO (-5600 2200);
DISPLAY INVISIBLE (-5600 2200);
FORCEPROP 1 LAST BODY_TYPE PLUMBING
J 0
(-5600 2150);
DISPLAY 1.595745 (-5600 2150);
PAINT GREEN (-5600 2150);
DISPLAY INVISIBLE (-5600 2150);
FORCEPROP 1 LAST HDL_TAP TRUE
J 0
(-5275 2075);
DISPLAY 1.595745 (-5275 2075);
PAINT GREEN (-5275 2075);
DISPLAY INVISIBLE (-5275 2075);
FORCEPROP 1 LAST PATH I35
J 0
(-5602 2200);
DISPLAY 0.872340 (-5602 2200);
PAINT GREEN (-5602 2200);
DISPLAY INVISIBLE (-5602 2200);
FORCEADD TAP..6
(-5600 2250);
FORCEPROP 3 LASTPIN (-5550 2250) SIG_NAME M_A_DQ<14>
J 0
(-5540 2260);
DISPLAY 0.659574 (-5540 2260);
PAINT MONO (-5540 2260);
DISPLAY INVISIBLE (-5540 2260);
FORCEPROP 1 LASTPIN (-5550 2250) BN 14
J 0
(-5602 2258);
DISPLAY 0.617021 (-5602 2258);
PAINT PINK (-5602 2258);
FORCEPROP 2 LAST CDS_LIB mstr_standard
J 0
(-5600 2250);
PAINT MONO (-5600 2250);
DISPLAY INVISIBLE (-5600 2250);
FORCEPROP 1 LAST BODY_TYPE PLUMBING
J 0
(-5600 2200);
DISPLAY 1.595745 (-5600 2200);
PAINT GREEN (-5600 2200);
DISPLAY INVISIBLE (-5600 2200);
FORCEPROP 1 LAST HDL_TAP TRUE
J 0
(-5275 2125);
DISPLAY 1.595745 (-5275 2125);
PAINT GREEN (-5275 2125);
DISPLAY INVISIBLE (-5275 2125);
FORCEPROP 1 LAST PATH I36
J 0
(-5602 2250);
DISPLAY 0.872340 (-5602 2250);
PAINT GREEN (-5602 2250);
DISPLAY INVISIBLE (-5602 2250);
FORCEADD TAP..6
(-5600 2300);
FORCEPROP 3 LASTPIN (-5550 2300) SIG_NAME M_A_DQ<15>
J 0
(-5540 2310);
DISPLAY 0.659574 (-5540 2310);
PAINT MONO (-5540 2310);
DISPLAY INVISIBLE (-5540 2310);
FORCEPROP 1 LASTPIN (-5550 2300) BN 15
J 0
(-5602 2308);
DISPLAY 0.617021 (-5602 2308);
PAINT PINK (-5602 2308);
FORCEPROP 2 LAST CDS_LIB mstr_standard
J 0
(-5600 2300);
PAINT MONO (-5600 2300);
DISPLAY INVISIBLE (-5600 2300);
FORCEPROP 1 LAST BODY_TYPE PLUMBING
J 0
(-5600 2250);
DISPLAY 1.595745 (-5600 2250);
PAINT GREEN (-5600 2250);
DISPLAY INVISIBLE (-5600 2250);
FORCEPROP 1 LAST HDL_TAP TRUE
J 0
(-5275 2175);
DISPLAY 1.595745 (-5275 2175);
PAINT GREEN (-5275 2175);
DISPLAY INVISIBLE (-5275 2175);
FORCEPROP 1 LAST PATH I37
J 0
(-5602 2300);
DISPLAY 0.872340 (-5602 2300);
PAINT GREEN (-5602 2300);
DISPLAY INVISIBLE (-5602 2300);
FORCEADD TAP..6
(-5600 2350);
FORCEPROP 3 LASTPIN (-5550 2350) SIG_NAME M_A_DQ<16>
J 0
(-5540 2360);
DISPLAY 0.659574 (-5540 2360);
PAINT MONO (-5540 2360);
DISPLAY INVISIBLE (-5540 2360);
FORCEPROP 1 LASTPIN (-5550 2350) BN 16
J 0
(-5602 2358);
DISPLAY 0.617021 (-5602 2358);
PAINT PINK (-5602 2358);
FORCEPROP 2 LAST CDS_LIB mstr_standard
J 0
(-5600 2350);
PAINT MONO (-5600 2350);
DISPLAY INVISIBLE (-5600 2350);
FORCEPROP 1 LAST BODY_TYPE PLUMBING
J 0
(-5600 2300);
DISPLAY 1.595745 (-5600 2300);
PAINT GREEN (-5600 2300);
DISPLAY INVISIBLE (-5600 2300);
FORCEPROP 1 LAST HDL_TAP TRUE
J 0
(-5275 2225);
DISPLAY 1.595745 (-5275 2225);
PAINT GREEN (-5275 2225);
DISPLAY INVISIBLE (-5275 2225);
FORCEPROP 1 LAST PATH I38
J 0
(-5602 2350);
DISPLAY 0.872340 (-5602 2350);
PAINT GREEN (-5602 2350);
DISPLAY INVISIBLE (-5602 2350);
FORCEADD TAP..6
(-5600 2400);
FORCEPROP 3 LASTPIN (-5550 2400) SIG_NAME M_A_DQ<17>
J 0
(-5540 2410);
DISPLAY 0.659574 (-5540 2410);
PAINT MONO (-5540 2410);
DISPLAY INVISIBLE (-5540 2410);
FORCEPROP 1 LASTPIN (-5550 2400) BN 17
J 0
(-5602 2408);
DISPLAY 0.617021 (-5602 2408);
PAINT PINK (-5602 2408);
FORCEPROP 2 LAST CDS_LIB mstr_standard
J 0
(-5600 2400);
PAINT MONO (-5600 2400);
DISPLAY INVISIBLE (-5600 2400);
FORCEPROP 1 LAST BODY_TYPE PLUMBING
J 0
(-5600 2350);
DISPLAY 1.595745 (-5600 2350);
PAINT GREEN (-5600 2350);
DISPLAY INVISIBLE (-5600 2350);
FORCEPROP 1 LAST HDL_TAP TRUE
J 0
(-5275 2275);
DISPLAY 1.595745 (-5275 2275);
PAINT GREEN (-5275 2275);
DISPLAY INVISIBLE (-5275 2275);
FORCEPROP 1 LAST PATH I39
J 0
(-5602 2400);
DISPLAY 0.872340 (-5602 2400);
PAINT GREEN (-5602 2400);
DISPLAY INVISIBLE (-5602 2400);
FORCEADD OFFPAGE..5
(-6450 550);
FORCEPROP 2 LAST $XR0 43 
J 0
(-6674 550);
DISPLAY 0.638298 (-6674 550);
PAINT MONO (-6674 550);
FORCEPROP 2 LAST $XR1 44 
J 0
(-6764 550);
DISPLAY 0.638298 (-6764 550);
PAINT MONO (-6764 550);
FORCEPROP 2 LAST CDS_LIB mstr_standard
J 0
(-6450 550);
PAINT MONO (-6450 550);
DISPLAY INVISIBLE (-6450 550);
FORCEPROP 1 LAST OFFPAGE TRUE
J 0
(-6125 425);
DISPLAY 1.170213 (-6125 425);
PAINT GREEN (-6125 425);
DISPLAY INVISIBLE (-6125 425);
FORCEPROP 1 LAST COMMENT_BODY TRUE
J 0
(-6350 475);
DISPLAY 1.170213 (-6350 475);
PAINT GREEN (-6350 475);
DISPLAY INVISIBLE (-6350 475);
FORCEPROP 2 LAST PATH I4
J 0
(-6400 625);
DISPLAY 1.021277 (-6400 625);
PAINT ORANGE (-6400 625);
DISPLAY INVISIBLE (-6400 625);
FORCEADD TAP..6
(-5600 2450);
FORCEPROP 3 LASTPIN (-5550 2450) SIG_NAME M_A_DQ<18>
J 0
(-5540 2460);
DISPLAY 0.659574 (-5540 2460);
PAINT MONO (-5540 2460);
DISPLAY INVISIBLE (-5540 2460);
FORCEPROP 1 LASTPIN (-5550 2450) BN 18
J 0
(-5602 2458);
DISPLAY 0.617021 (-5602 2458);
PAINT PINK (-5602 2458);
FORCEPROP 2 LAST CDS_LIB mstr_standard
J 0
(-5600 2450);
PAINT MONO (-5600 2450);
DISPLAY INVISIBLE (-5600 2450);
FORCEPROP 1 LAST BODY_TYPE PLUMBING
J 0
(-5600 2400);
DISPLAY 1.595745 (-5600 2400);
PAINT GREEN (-5600 2400);
DISPLAY INVISIBLE (-5600 2400);
FORCEPROP 1 LAST HDL_TAP TRUE
J 0
(-5275 2325);
DISPLAY 1.595745 (-5275 2325);
PAINT GREEN (-5275 2325);
DISPLAY INVISIBLE (-5275 2325);
FORCEPROP 1 LAST PATH I40
J 0
(-5602 2450);
DISPLAY 0.872340 (-5602 2450);
PAINT GREEN (-5602 2450);
DISPLAY INVISIBLE (-5602 2450);
FORCEADD TAP..6
(-5600 2500);
FORCEPROP 3 LASTPIN (-5550 2500) SIG_NAME M_A_DQ<19>
J 0
(-5540 2510);
DISPLAY 0.659574 (-5540 2510);
PAINT MONO (-5540 2510);
DISPLAY INVISIBLE (-5540 2510);
FORCEPROP 1 LASTPIN (-5550 2500) BN 19
J 0
(-5602 2508);
DISPLAY 0.617021 (-5602 2508);
PAINT PINK (-5602 2508);
FORCEPROP 2 LAST CDS_LIB mstr_standard
J 0
(-5600 2500);
PAINT MONO (-5600 2500);
DISPLAY INVISIBLE (-5600 2500);
FORCEPROP 1 LAST BODY_TYPE PLUMBING
J 0
(-5600 2450);
DISPLAY 1.595745 (-5600 2450);
PAINT GREEN (-5600 2450);
DISPLAY INVISIBLE (-5600 2450);
FORCEPROP 1 LAST HDL_TAP TRUE
J 0
(-5275 2375);
DISPLAY 1.595745 (-5275 2375);
PAINT GREEN (-5275 2375);
DISPLAY INVISIBLE (-5275 2375);
FORCEPROP 1 LAST PATH I41
J 0
(-5602 2500);
DISPLAY 0.872340 (-5602 2500);
PAINT GREEN (-5602 2500);
DISPLAY INVISIBLE (-5602 2500);
FORCEADD TAP..6
(-5600 2550);
FORCEPROP 3 LASTPIN (-5550 2550) SIG_NAME M_A_DQ<20>
J 0
(-5540 2560);
DISPLAY 0.659574 (-5540 2560);
PAINT MONO (-5540 2560);
DISPLAY INVISIBLE (-5540 2560);
FORCEPROP 1 LASTPIN (-5550 2550) BN 20
J 0
(-5602 2558);
DISPLAY 0.617021 (-5602 2558);
PAINT PINK (-5602 2558);
FORCEPROP 2 LAST CDS_LIB mstr_standard
J 0
(-5600 2550);
PAINT MONO (-5600 2550);
DISPLAY INVISIBLE (-5600 2550);
FORCEPROP 1 LAST BODY_TYPE PLUMBING
J 0
(-5600 2500);
DISPLAY 1.595745 (-5600 2500);
PAINT GREEN (-5600 2500);
DISPLAY INVISIBLE (-5600 2500);
FORCEPROP 1 LAST HDL_TAP TRUE
J 0
(-5275 2425);
DISPLAY 1.595745 (-5275 2425);
PAINT GREEN (-5275 2425);
DISPLAY INVISIBLE (-5275 2425);
FORCEPROP 1 LAST PATH I42
J 0
(-5602 2550);
DISPLAY 0.872340 (-5602 2550);
PAINT GREEN (-5602 2550);
DISPLAY INVISIBLE (-5602 2550);
FORCEADD TAP..6
(-5600 2600);
FORCEPROP 3 LASTPIN (-5550 2600) SIG_NAME M_A_DQ<21>
J 0
(-5540 2610);
DISPLAY 0.659574 (-5540 2610);
PAINT MONO (-5540 2610);
DISPLAY INVISIBLE (-5540 2610);
FORCEPROP 1 LASTPIN (-5550 2600) BN 21
J 0
(-5602 2608);
DISPLAY 0.617021 (-5602 2608);
PAINT PINK (-5602 2608);
FORCEPROP 2 LAST CDS_LIB mstr_standard
J 0
(-5600 2600);
PAINT MONO (-5600 2600);
DISPLAY INVISIBLE (-5600 2600);
FORCEPROP 1 LAST BODY_TYPE PLUMBING
J 0
(-5600 2550);
DISPLAY 1.595745 (-5600 2550);
PAINT GREEN (-5600 2550);
DISPLAY INVISIBLE (-5600 2550);
FORCEPROP 1 LAST HDL_TAP TRUE
J 0
(-5275 2475);
DISPLAY 1.595745 (-5275 2475);
PAINT GREEN (-5275 2475);
DISPLAY INVISIBLE (-5275 2475);
FORCEPROP 1 LAST PATH I43
J 0
(-5602 2600);
DISPLAY 0.872340 (-5602 2600);
PAINT GREEN (-5602 2600);
DISPLAY INVISIBLE (-5602 2600);
FORCEADD TAP..6
(-5600 2650);
FORCEPROP 3 LASTPIN (-5550 2650) SIG_NAME M_A_DQ<22>
J 0
(-5540 2660);
DISPLAY 0.659574 (-5540 2660);
PAINT MONO (-5540 2660);
DISPLAY INVISIBLE (-5540 2660);
FORCEPROP 1 LASTPIN (-5550 2650) BN 22
J 0
(-5602 2658);
DISPLAY 0.617021 (-5602 2658);
PAINT PINK (-5602 2658);
FORCEPROP 2 LAST CDS_LIB mstr_standard
J 0
(-5600 2650);
PAINT MONO (-5600 2650);
DISPLAY INVISIBLE (-5600 2650);
FORCEPROP 1 LAST BODY_TYPE PLUMBING
J 0
(-5600 2600);
DISPLAY 1.595745 (-5600 2600);
PAINT GREEN (-5600 2600);
DISPLAY INVISIBLE (-5600 2600);
FORCEPROP 1 LAST HDL_TAP TRUE
J 0
(-5275 2525);
DISPLAY 1.595745 (-5275 2525);
PAINT GREEN (-5275 2525);
DISPLAY INVISIBLE (-5275 2525);
FORCEPROP 1 LAST PATH I44
J 0
(-5602 2650);
DISPLAY 0.872340 (-5602 2650);
PAINT GREEN (-5602 2650);
DISPLAY INVISIBLE (-5602 2650);
FORCEADD TAP..6
(-5600 2700);
FORCEPROP 3 LASTPIN (-5550 2700) SIG_NAME M_A_DQ<23>
J 0
(-5540 2710);
DISPLAY 0.659574 (-5540 2710);
PAINT MONO (-5540 2710);
DISPLAY INVISIBLE (-5540 2710);
FORCEPROP 1 LASTPIN (-5550 2700) BN 23
J 0
(-5602 2708);
DISPLAY 0.617021 (-5602 2708);
PAINT PINK (-5602 2708);
FORCEPROP 2 LAST CDS_LIB mstr_standard
J 0
(-5600 2700);
PAINT MONO (-5600 2700);
DISPLAY INVISIBLE (-5600 2700);
FORCEPROP 1 LAST BODY_TYPE PLUMBING
J 0
(-5600 2650);
DISPLAY 1.595745 (-5600 2650);
PAINT GREEN (-5600 2650);
DISPLAY INVISIBLE (-5600 2650);
FORCEPROP 1 LAST HDL_TAP TRUE
J 0
(-5275 2575);
DISPLAY 1.595745 (-5275 2575);
PAINT GREEN (-5275 2575);
DISPLAY INVISIBLE (-5275 2575);
FORCEPROP 1 LAST PATH I45
J 0
(-5602 2700);
DISPLAY 0.872340 (-5602 2700);
PAINT GREEN (-5602 2700);
DISPLAY INVISIBLE (-5602 2700);
FORCEADD TAP..6
(-5600 2750);
FORCEPROP 3 LASTPIN (-5550 2750) SIG_NAME M_A_DQ<24>
J 0
(-5540 2760);
DISPLAY 0.659574 (-5540 2760);
PAINT MONO (-5540 2760);
DISPLAY INVISIBLE (-5540 2760);
FORCEPROP 1 LASTPIN (-5550 2750) BN 24
J 0
(-5602 2758);
DISPLAY 0.617021 (-5602 2758);
PAINT PINK (-5602 2758);
FORCEPROP 2 LAST CDS_LIB mstr_standard
J 0
(-5600 2750);
PAINT MONO (-5600 2750);
DISPLAY INVISIBLE (-5600 2750);
FORCEPROP 1 LAST BODY_TYPE PLUMBING
J 0
(-5600 2700);
DISPLAY 1.595745 (-5600 2700);
PAINT GREEN (-5600 2700);
DISPLAY INVISIBLE (-5600 2700);
FORCEPROP 1 LAST HDL_TAP TRUE
J 0
(-5275 2625);
DISPLAY 1.595745 (-5275 2625);
PAINT GREEN (-5275 2625);
DISPLAY INVISIBLE (-5275 2625);
FORCEPROP 1 LAST PATH I46
J 0
(-5602 2750);
DISPLAY 0.872340 (-5602 2750);
PAINT GREEN (-5602 2750);
DISPLAY INVISIBLE (-5602 2750);
FORCEADD TAP..6
(-5600 2850);
FORCEPROP 3 LASTPIN (-5550 2850) SIG_NAME M_A_DQ<26>
J 0
(-5540 2860);
DISPLAY 0.659574 (-5540 2860);
PAINT MONO (-5540 2860);
DISPLAY INVISIBLE (-5540 2860);
FORCEPROP 1 LASTPIN (-5550 2850) BN 26
J 0
(-5602 2858);
DISPLAY 0.617021 (-5602 2858);
PAINT PINK (-5602 2858);
FORCEPROP 2 LAST CDS_LIB mstr_standard
J 0
(-5600 2850);
PAINT MONO (-5600 2850);
DISPLAY INVISIBLE (-5600 2850);
FORCEPROP 1 LAST BODY_TYPE PLUMBING
J 0
(-5600 2800);
DISPLAY 1.595745 (-5600 2800);
PAINT GREEN (-5600 2800);
DISPLAY INVISIBLE (-5600 2800);
FORCEPROP 1 LAST HDL_TAP TRUE
J 0
(-5275 2725);
DISPLAY 1.595745 (-5275 2725);
PAINT GREEN (-5275 2725);
DISPLAY INVISIBLE (-5275 2725);
FORCEPROP 1 LAST PATH I47
J 0
(-5602 2850);
DISPLAY 0.872340 (-5602 2850);
PAINT GREEN (-5602 2850);
DISPLAY INVISIBLE (-5602 2850);
FORCEADD TAP..6
(-5600 2800);
FORCEPROP 3 LASTPIN (-5550 2800) SIG_NAME M_A_DQ<25>
J 0
(-5540 2810);
DISPLAY 0.659574 (-5540 2810);
PAINT MONO (-5540 2810);
DISPLAY INVISIBLE (-5540 2810);
FORCEPROP 1 LASTPIN (-5550 2800) BN 25
J 0
(-5602 2808);
DISPLAY 0.617021 (-5602 2808);
PAINT PINK (-5602 2808);
FORCEPROP 2 LAST CDS_LIB mstr_standard
J 0
(-5600 2800);
PAINT MONO (-5600 2800);
DISPLAY INVISIBLE (-5600 2800);
FORCEPROP 1 LAST BODY_TYPE PLUMBING
J 0
(-5600 2750);
DISPLAY 1.595745 (-5600 2750);
PAINT GREEN (-5600 2750);
DISPLAY INVISIBLE (-5600 2750);
FORCEPROP 1 LAST HDL_TAP TRUE
J 0
(-5275 2675);
DISPLAY 1.595745 (-5275 2675);
PAINT GREEN (-5275 2675);
DISPLAY INVISIBLE (-5275 2675);
FORCEPROP 1 LAST PATH I48
J 0
(-5602 2800);
DISPLAY 0.872340 (-5602 2800);
PAINT GREEN (-5602 2800);
DISPLAY INVISIBLE (-5602 2800);
FORCEADD TAP..6
(-5600 2900);
FORCEPROP 3 LASTPIN (-5550 2900) SIG_NAME M_A_DQ<27>
J 0
(-5540 2910);
DISPLAY 0.659574 (-5540 2910);
PAINT MONO (-5540 2910);
DISPLAY INVISIBLE (-5540 2910);
FORCEPROP 1 LASTPIN (-5550 2900) BN 27
J 0
(-5602 2908);
DISPLAY 0.617021 (-5602 2908);
PAINT PINK (-5602 2908);
FORCEPROP 2 LAST CDS_LIB mstr_standard
J 0
(-5600 2900);
PAINT MONO (-5600 2900);
DISPLAY INVISIBLE (-5600 2900);
FORCEPROP 1 LAST BODY_TYPE PLUMBING
J 0
(-5600 2850);
DISPLAY 1.595745 (-5600 2850);
PAINT GREEN (-5600 2850);
DISPLAY INVISIBLE (-5600 2850);
FORCEPROP 1 LAST HDL_TAP TRUE
J 0
(-5275 2775);
DISPLAY 1.595745 (-5275 2775);
PAINT GREEN (-5275 2775);
DISPLAY INVISIBLE (-5275 2775);
FORCEPROP 1 LAST PATH I49
J 0
(-5602 2900);
DISPLAY 0.872340 (-5602 2900);
PAINT GREEN (-5602 2900);
DISPLAY INVISIBLE (-5602 2900);
FORCEADD TAP..6
(-5600 650);
FORCEPROP 3 LASTPIN (-5550 650) SIG_NAME M_A_CLK_DN<0>
J 0
(-5540 660);
DISPLAY 0.659574 (-5540 660);
PAINT MONO (-5540 660);
DISPLAY INVISIBLE (-5540 660);
FORCEPROP 1 LASTPIN (-5550 650) BN 0
J 0
(-5602 658);
DISPLAY 0.617021 (-5602 658);
PAINT PINK (-5602 658);
FORCEPROP 2 LAST CDS_LIB mstr_standard
J 0
(-5600 650);
PAINT MONO (-5600 650);
DISPLAY INVISIBLE (-5600 650);
FORCEPROP 1 LAST BODY_TYPE PLUMBING
J 0
(-5600 600);
DISPLAY 1.595745 (-5600 600);
PAINT GREEN (-5600 600);
DISPLAY INVISIBLE (-5600 600);
FORCEPROP 1 LAST HDL_TAP TRUE
J 0
(-5275 525);
DISPLAY 1.595745 (-5275 525);
PAINT GREEN (-5275 525);
DISPLAY INVISIBLE (-5275 525);
FORCEPROP 1 LAST PATH I5
J 0
(-5602 650);
DISPLAY 0.872340 (-5602 650);
PAINT GREEN (-5602 650);
DISPLAY INVISIBLE (-5602 650);
FORCEADD TAP..6
(-5600 2950);
FORCEPROP 3 LASTPIN (-5550 2950) SIG_NAME M_A_DQ<28>
J 0
(-5540 2960);
DISPLAY 0.659574 (-5540 2960);
PAINT MONO (-5540 2960);
DISPLAY INVISIBLE (-5540 2960);
FORCEPROP 1 LASTPIN (-5550 2950) BN 28
J 0
(-5602 2958);
DISPLAY 0.617021 (-5602 2958);
PAINT PINK (-5602 2958);
FORCEPROP 2 LAST CDS_LIB mstr_standard
J 0
(-5600 2950);
PAINT MONO (-5600 2950);
DISPLAY INVISIBLE (-5600 2950);
FORCEPROP 1 LAST BODY_TYPE PLUMBING
J 0
(-5600 2900);
DISPLAY 1.595745 (-5600 2900);
PAINT GREEN (-5600 2900);
DISPLAY INVISIBLE (-5600 2900);
FORCEPROP 1 LAST HDL_TAP TRUE
J 0
(-5275 2825);
DISPLAY 1.595745 (-5275 2825);
PAINT GREEN (-5275 2825);
DISPLAY INVISIBLE (-5275 2825);
FORCEPROP 1 LAST PATH I50
J 0
(-5602 2950);
DISPLAY 0.872340 (-5602 2950);
PAINT GREEN (-5602 2950);
DISPLAY INVISIBLE (-5602 2950);
FORCEADD TAP..6
(-5600 3000);
FORCEPROP 3 LASTPIN (-5550 3000) SIG_NAME M_A_DQ<29>
J 0
(-5540 3010);
DISPLAY 0.659574 (-5540 3010);
PAINT MONO (-5540 3010);
DISPLAY INVISIBLE (-5540 3010);
FORCEPROP 1 LASTPIN (-5550 3000) BN 29
J 0
(-5602 3008);
DISPLAY 0.617021 (-5602 3008);
PAINT PINK (-5602 3008);
FORCEPROP 2 LAST CDS_LIB mstr_standard
J 0
(-5600 3000);
PAINT MONO (-5600 3000);
DISPLAY INVISIBLE (-5600 3000);
FORCEPROP 1 LAST BODY_TYPE PLUMBING
J 0
(-5600 2950);
DISPLAY 1.595745 (-5600 2950);
PAINT GREEN (-5600 2950);
DISPLAY INVISIBLE (-5600 2950);
FORCEPROP 1 LAST HDL_TAP TRUE
J 0
(-5275 2875);
DISPLAY 1.595745 (-5275 2875);
PAINT GREEN (-5275 2875);
DISPLAY INVISIBLE (-5275 2875);
FORCEPROP 1 LAST PATH I51
J 0
(-5602 3000);
DISPLAY 0.872340 (-5602 3000);
PAINT GREEN (-5602 3000);
DISPLAY INVISIBLE (-5602 3000);
FORCEADD TAP..6
(-5600 3100);
FORCEPROP 3 LASTPIN (-5550 3100) SIG_NAME M_A_DQ<31>
J 0
(-5540 3110);
DISPLAY 0.659574 (-5540 3110);
PAINT MONO (-5540 3110);
DISPLAY INVISIBLE (-5540 3110);
FORCEPROP 1 LASTPIN (-5550 3100) BN 31
J 0
(-5602 3108);
DISPLAY 0.617021 (-5602 3108);
PAINT PINK (-5602 3108);
FORCEPROP 2 LAST CDS_LIB mstr_standard
J 0
(-5600 3100);
PAINT MONO (-5600 3100);
DISPLAY INVISIBLE (-5600 3100);
FORCEPROP 1 LAST BODY_TYPE PLUMBING
J 0
(-5600 3050);
DISPLAY 1.595745 (-5600 3050);
PAINT GREEN (-5600 3050);
DISPLAY INVISIBLE (-5600 3050);
FORCEPROP 1 LAST HDL_TAP TRUE
J 0
(-5275 2975);
DISPLAY 1.595745 (-5275 2975);
PAINT GREEN (-5275 2975);
DISPLAY INVISIBLE (-5275 2975);
FORCEPROP 1 LAST PATH I52
J 0
(-5602 3100);
DISPLAY 0.872340 (-5602 3100);
PAINT GREEN (-5602 3100);
DISPLAY INVISIBLE (-5602 3100);
FORCEADD TAP..6
(-5600 3050);
FORCEPROP 3 LASTPIN (-5550 3050) SIG_NAME M_A_DQ<30>
J 0
(-5540 3060);
DISPLAY 0.659574 (-5540 3060);
PAINT MONO (-5540 3060);
DISPLAY INVISIBLE (-5540 3060);
FORCEPROP 1 LASTPIN (-5550 3050) BN 30
J 0
(-5602 3058);
DISPLAY 0.617021 (-5602 3058);
PAINT PINK (-5602 3058);
FORCEPROP 2 LAST CDS_LIB mstr_standard
J 0
(-5600 3050);
PAINT MONO (-5600 3050);
DISPLAY INVISIBLE (-5600 3050);
FORCEPROP 1 LAST BODY_TYPE PLUMBING
J 0
(-5600 3000);
DISPLAY 1.595745 (-5600 3000);
PAINT GREEN (-5600 3000);
DISPLAY INVISIBLE (-5600 3000);
FORCEPROP 1 LAST HDL_TAP TRUE
J 0
(-5275 2925);
DISPLAY 1.595745 (-5275 2925);
PAINT GREEN (-5275 2925);
DISPLAY INVISIBLE (-5275 2925);
FORCEPROP 1 LAST PATH I53
J 0
(-5602 3050);
DISPLAY 0.872340 (-5602 3050);
PAINT GREEN (-5602 3050);
DISPLAY INVISIBLE (-5602 3050);
FORCEADD TAP..6
(-5600 3150);
FORCEPROP 3 LASTPIN (-5550 3150) SIG_NAME M_A_DQ<32>
J 0
(-5540 3160);
DISPLAY 0.659574 (-5540 3160);
PAINT MONO (-5540 3160);
DISPLAY INVISIBLE (-5540 3160);
FORCEPROP 1 LASTPIN (-5550 3150) BN 32
J 0
(-5602 3158);
DISPLAY 0.617021 (-5602 3158);
PAINT PINK (-5602 3158);
FORCEPROP 2 LAST CDS_LIB mstr_standard
J 0
(-5600 3150);
PAINT MONO (-5600 3150);
DISPLAY INVISIBLE (-5600 3150);
FORCEPROP 1 LAST BODY_TYPE PLUMBING
J 0
(-5600 3100);
DISPLAY 1.595745 (-5600 3100);
PAINT GREEN (-5600 3100);
DISPLAY INVISIBLE (-5600 3100);
FORCEPROP 1 LAST HDL_TAP TRUE
J 0
(-5275 3025);
DISPLAY 1.595745 (-5275 3025);
PAINT GREEN (-5275 3025);
DISPLAY INVISIBLE (-5275 3025);
FORCEPROP 1 LAST PATH I54
J 0
(-5602 3150);
DISPLAY 0.872340 (-5602 3150);
PAINT GREEN (-5602 3150);
DISPLAY INVISIBLE (-5602 3150);
FORCEADD TAP..6
(-5600 3200);
FORCEPROP 3 LASTPIN (-5550 3200) SIG_NAME M_A_DQ<33>
J 0
(-5540 3210);
DISPLAY 0.659574 (-5540 3210);
PAINT MONO (-5540 3210);
DISPLAY INVISIBLE (-5540 3210);
FORCEPROP 1 LASTPIN (-5550 3200) BN 33
J 0
(-5602 3208);
DISPLAY 0.617021 (-5602 3208);
PAINT PINK (-5602 3208);
FORCEPROP 2 LAST CDS_LIB mstr_standard
J 0
(-5600 3200);
PAINT MONO (-5600 3200);
DISPLAY INVISIBLE (-5600 3200);
FORCEPROP 1 LAST BODY_TYPE PLUMBING
J 0
(-5600 3150);
DISPLAY 1.595745 (-5600 3150);
PAINT GREEN (-5600 3150);
DISPLAY INVISIBLE (-5600 3150);
FORCEPROP 1 LAST HDL_TAP TRUE
J 0
(-5275 3075);
DISPLAY 1.595745 (-5275 3075);
PAINT GREEN (-5275 3075);
DISPLAY INVISIBLE (-5275 3075);
FORCEPROP 1 LAST PATH I55
J 0
(-5602 3200);
DISPLAY 0.872340 (-5602 3200);
PAINT GREEN (-5602 3200);
DISPLAY INVISIBLE (-5602 3200);
FORCEADD TAP..6
(-5600 3250);
FORCEPROP 3 LASTPIN (-5550 3250) SIG_NAME M_A_DQ<34>
J 0
(-5540 3260);
DISPLAY 0.659574 (-5540 3260);
PAINT MONO (-5540 3260);
DISPLAY INVISIBLE (-5540 3260);
FORCEPROP 1 LASTPIN (-5550 3250) BN 34
J 0
(-5602 3258);
DISPLAY 0.617021 (-5602 3258);
PAINT PINK (-5602 3258);
FORCEPROP 2 LAST CDS_LIB mstr_standard
J 0
(-5600 3250);
PAINT MONO (-5600 3250);
DISPLAY INVISIBLE (-5600 3250);
FORCEPROP 1 LAST BODY_TYPE PLUMBING
J 0
(-5600 3200);
DISPLAY 1.595745 (-5600 3200);
PAINT GREEN (-5600 3200);
DISPLAY INVISIBLE (-5600 3200);
FORCEPROP 1 LAST HDL_TAP TRUE
J 0
(-5275 3125);
DISPLAY 1.595745 (-5275 3125);
PAINT GREEN (-5275 3125);
DISPLAY INVISIBLE (-5275 3125);
FORCEPROP 1 LAST PATH I56
J 0
(-5602 3250);
DISPLAY 0.872340 (-5602 3250);
PAINT GREEN (-5602 3250);
DISPLAY INVISIBLE (-5602 3250);
FORCEADD TAP..6
(-5600 3350);
FORCEPROP 3 LASTPIN (-5550 3350) SIG_NAME M_A_DQ<36>
J 0
(-5540 3360);
DISPLAY 0.659574 (-5540 3360);
PAINT MONO (-5540 3360);
DISPLAY INVISIBLE (-5540 3360);
FORCEPROP 1 LASTPIN (-5550 3350) BN 36
J 0
(-5602 3358);
DISPLAY 0.617021 (-5602 3358);
PAINT PINK (-5602 3358);
FORCEPROP 2 LAST CDS_LIB mstr_standard
J 0
(-5600 3350);
PAINT MONO (-5600 3350);
DISPLAY INVISIBLE (-5600 3350);
FORCEPROP 1 LAST BODY_TYPE PLUMBING
J 0
(-5600 3300);
DISPLAY 1.595745 (-5600 3300);
PAINT GREEN (-5600 3300);
DISPLAY INVISIBLE (-5600 3300);
FORCEPROP 1 LAST HDL_TAP TRUE
J 0
(-5275 3225);
DISPLAY 1.595745 (-5275 3225);
PAINT GREEN (-5275 3225);
DISPLAY INVISIBLE (-5275 3225);
FORCEPROP 1 LAST PATH I57
J 0
(-5602 3350);
DISPLAY 0.872340 (-5602 3350);
PAINT GREEN (-5602 3350);
DISPLAY INVISIBLE (-5602 3350);
FORCEADD TAP..6
(-5600 3300);
FORCEPROP 3 LASTPIN (-5550 3300) SIG_NAME M_A_DQ<35>
J 0
(-5540 3310);
DISPLAY 0.659574 (-5540 3310);
PAINT MONO (-5540 3310);
DISPLAY INVISIBLE (-5540 3310);
FORCEPROP 1 LASTPIN (-5550 3300) BN 35
J 0
(-5602 3308);
DISPLAY 0.617021 (-5602 3308);
PAINT PINK (-5602 3308);
FORCEPROP 2 LAST CDS_LIB mstr_standard
J 0
(-5600 3300);
PAINT MONO (-5600 3300);
DISPLAY INVISIBLE (-5600 3300);
FORCEPROP 1 LAST BODY_TYPE PLUMBING
J 0
(-5600 3250);
DISPLAY 1.595745 (-5600 3250);
PAINT GREEN (-5600 3250);
DISPLAY INVISIBLE (-5600 3250);
FORCEPROP 1 LAST HDL_TAP TRUE
J 0
(-5275 3175);
DISPLAY 1.595745 (-5275 3175);
PAINT GREEN (-5275 3175);
DISPLAY INVISIBLE (-5275 3175);
FORCEPROP 1 LAST PATH I58
J 0
(-5602 3300);
DISPLAY 0.872340 (-5602 3300);
PAINT GREEN (-5602 3300);
DISPLAY INVISIBLE (-5602 3300);
FORCEADD TAP..6
(-5600 3400);
FORCEPROP 3 LASTPIN (-5550 3400) SIG_NAME M_A_DQ<37>
J 0
(-5540 3410);
DISPLAY 0.659574 (-5540 3410);
PAINT MONO (-5540 3410);
DISPLAY INVISIBLE (-5540 3410);
FORCEPROP 1 LASTPIN (-5550 3400) BN 37
J 0
(-5602 3408);
DISPLAY 0.617021 (-5602 3408);
PAINT PINK (-5602 3408);
FORCEPROP 2 LAST CDS_LIB mstr_standard
J 0
(-5600 3400);
PAINT MONO (-5600 3400);
DISPLAY INVISIBLE (-5600 3400);
FORCEPROP 1 LAST BODY_TYPE PLUMBING
J 0
(-5600 3350);
DISPLAY 1.595745 (-5600 3350);
PAINT GREEN (-5600 3350);
DISPLAY INVISIBLE (-5600 3350);
FORCEPROP 1 LAST HDL_TAP TRUE
J 0
(-5275 3275);
DISPLAY 1.595745 (-5275 3275);
PAINT GREEN (-5275 3275);
DISPLAY INVISIBLE (-5275 3275);
FORCEPROP 1 LAST PATH I59
J 0
(-5602 3400);
DISPLAY 0.872340 (-5602 3400);
PAINT GREEN (-5602 3400);
DISPLAY INVISIBLE (-5602 3400);
FORCEADD TAP..6
(-5600 700);
FORCEPROP 3 LASTPIN (-5550 700) SIG_NAME M_A_CLK_DN<1>
J 0
(-5540 710);
DISPLAY 0.659574 (-5540 710);
PAINT MONO (-5540 710);
DISPLAY INVISIBLE (-5540 710);
FORCEPROP 1 LASTPIN (-5550 700) BN 1
J 0
(-5602 708);
DISPLAY 0.617021 (-5602 708);
PAINT PINK (-5602 708);
FORCEPROP 2 LAST CDS_LIB mstr_standard
J 0
(-5600 700);
PAINT MONO (-5600 700);
DISPLAY INVISIBLE (-5600 700);
FORCEPROP 1 LAST BODY_TYPE PLUMBING
J 0
(-5600 650);
DISPLAY 1.595745 (-5600 650);
PAINT GREEN (-5600 650);
DISPLAY INVISIBLE (-5600 650);
FORCEPROP 1 LAST HDL_TAP TRUE
J 0
(-5275 575);
DISPLAY 1.595745 (-5275 575);
PAINT GREEN (-5275 575);
DISPLAY INVISIBLE (-5275 575);
FORCEPROP 1 LAST PATH I6
J 0
(-5602 700);
DISPLAY 0.872340 (-5602 700);
PAINT GREEN (-5602 700);
DISPLAY INVISIBLE (-5602 700);
FORCEADD TAP..6
(-5600 3450);
FORCEPROP 3 LASTPIN (-5550 3450) SIG_NAME M_A_DQ<38>
J 0
(-5540 3460);
DISPLAY 0.659574 (-5540 3460);
PAINT MONO (-5540 3460);
DISPLAY INVISIBLE (-5540 3460);
FORCEPROP 1 LASTPIN (-5550 3450) BN 38
J 0
(-5602 3458);
DISPLAY 0.617021 (-5602 3458);
PAINT PINK (-5602 3458);
FORCEPROP 2 LAST CDS_LIB mstr_standard
J 0
(-5600 3450);
PAINT MONO (-5600 3450);
DISPLAY INVISIBLE (-5600 3450);
FORCEPROP 1 LAST BODY_TYPE PLUMBING
J 0
(-5600 3400);
DISPLAY 1.595745 (-5600 3400);
PAINT GREEN (-5600 3400);
DISPLAY INVISIBLE (-5600 3400);
FORCEPROP 1 LAST HDL_TAP TRUE
J 0
(-5275 3325);
DISPLAY 1.595745 (-5275 3325);
PAINT GREEN (-5275 3325);
DISPLAY INVISIBLE (-5275 3325);
FORCEPROP 1 LAST PATH I60
J 0
(-5602 3450);
DISPLAY 0.872340 (-5602 3450);
PAINT GREEN (-5602 3450);
DISPLAY INVISIBLE (-5602 3450);
FORCEADD TAP..6
(-5600 3500);
FORCEPROP 3 LASTPIN (-5550 3500) SIG_NAME M_A_DQ<39>
J 0
(-5540 3510);
DISPLAY 0.659574 (-5540 3510);
PAINT MONO (-5540 3510);
DISPLAY INVISIBLE (-5540 3510);
FORCEPROP 1 LASTPIN (-5550 3500) BN 39
J 0
(-5602 3508);
DISPLAY 0.617021 (-5602 3508);
PAINT PINK (-5602 3508);
FORCEPROP 2 LAST CDS_LIB mstr_standard
J 0
(-5600 3500);
PAINT MONO (-5600 3500);
DISPLAY INVISIBLE (-5600 3500);
FORCEPROP 1 LAST BODY_TYPE PLUMBING
J 0
(-5600 3450);
DISPLAY 1.595745 (-5600 3450);
PAINT GREEN (-5600 3450);
DISPLAY INVISIBLE (-5600 3450);
FORCEPROP 1 LAST HDL_TAP TRUE
J 0
(-5275 3375);
DISPLAY 1.595745 (-5275 3375);
PAINT GREEN (-5275 3375);
DISPLAY INVISIBLE (-5275 3375);
FORCEPROP 1 LAST PATH I61
J 0
(-5602 3500);
DISPLAY 0.872340 (-5602 3500);
PAINT GREEN (-5602 3500);
DISPLAY INVISIBLE (-5602 3500);
FORCEADD TAP..6
(-5600 3550);
FORCEPROP 3 LASTPIN (-5550 3550) SIG_NAME M_A_DQ<40>
J 0
(-5540 3560);
DISPLAY 0.659574 (-5540 3560);
PAINT MONO (-5540 3560);
DISPLAY INVISIBLE (-5540 3560);
FORCEPROP 1 LASTPIN (-5550 3550) BN 40
J 0
(-5602 3558);
DISPLAY 0.617021 (-5602 3558);
PAINT PINK (-5602 3558);
FORCEPROP 2 LAST CDS_LIB mstr_standard
J 0
(-5600 3550);
PAINT MONO (-5600 3550);
DISPLAY INVISIBLE (-5600 3550);
FORCEPROP 1 LAST BODY_TYPE PLUMBING
J 0
(-5600 3500);
DISPLAY 1.595745 (-5600 3500);
PAINT GREEN (-5600 3500);
DISPLAY INVISIBLE (-5600 3500);
FORCEPROP 1 LAST HDL_TAP TRUE
J 0
(-5275 3425);
DISPLAY 1.595745 (-5275 3425);
PAINT GREEN (-5275 3425);
DISPLAY INVISIBLE (-5275 3425);
FORCEPROP 1 LAST PATH I62
J 0
(-5602 3550);
DISPLAY 0.872340 (-5602 3550);
PAINT GREEN (-5602 3550);
DISPLAY INVISIBLE (-5602 3550);
FORCEADD TAP..6
(-5600 3600);
FORCEPROP 3 LASTPIN (-5550 3600) SIG_NAME M_A_DQ<41>
J 0
(-5540 3610);
DISPLAY 0.659574 (-5540 3610);
PAINT MONO (-5540 3610);
DISPLAY INVISIBLE (-5540 3610);
FORCEPROP 1 LASTPIN (-5550 3600) BN 41
J 0
(-5602 3608);
DISPLAY 0.617021 (-5602 3608);
PAINT PINK (-5602 3608);
FORCEPROP 2 LAST CDS_LIB mstr_standard
J 0
(-5600 3600);
PAINT MONO (-5600 3600);
DISPLAY INVISIBLE (-5600 3600);
FORCEPROP 1 LAST BODY_TYPE PLUMBING
J 0
(-5600 3550);
DISPLAY 1.595745 (-5600 3550);
PAINT GREEN (-5600 3550);
DISPLAY INVISIBLE (-5600 3550);
FORCEPROP 1 LAST HDL_TAP TRUE
J 0
(-5275 3475);
DISPLAY 1.595745 (-5275 3475);
PAINT GREEN (-5275 3475);
DISPLAY INVISIBLE (-5275 3475);
FORCEPROP 1 LAST PATH I63
J 0
(-5602 3600);
DISPLAY 0.872340 (-5602 3600);
PAINT GREEN (-5602 3600);
DISPLAY INVISIBLE (-5602 3600);
FORCEADD TAP..6
(-5600 3650);
FORCEPROP 3 LASTPIN (-5550 3650) SIG_NAME M_A_DQ<42>
J 0
(-5540 3660);
DISPLAY 0.659574 (-5540 3660);
PAINT MONO (-5540 3660);
DISPLAY INVISIBLE (-5540 3660);
FORCEPROP 1 LASTPIN (-5550 3650) BN 42
J 0
(-5602 3658);
DISPLAY 0.617021 (-5602 3658);
PAINT PINK (-5602 3658);
FORCEPROP 2 LAST CDS_LIB mstr_standard
J 0
(-5600 3650);
PAINT MONO (-5600 3650);
DISPLAY INVISIBLE (-5600 3650);
FORCEPROP 1 LAST BODY_TYPE PLUMBING
J 0
(-5600 3600);
DISPLAY 1.595745 (-5600 3600);
PAINT GREEN (-5600 3600);
DISPLAY INVISIBLE (-5600 3600);
FORCEPROP 1 LAST HDL_TAP TRUE
J 0
(-5275 3525);
DISPLAY 1.595745 (-5275 3525);
PAINT GREEN (-5275 3525);
DISPLAY INVISIBLE (-5275 3525);
FORCEPROP 1 LAST PATH I64
J 0
(-5602 3650);
DISPLAY 0.872340 (-5602 3650);
PAINT GREEN (-5602 3650);
DISPLAY INVISIBLE (-5602 3650);
FORCEADD TAP..6
(-5600 3700);
FORCEPROP 3 LASTPIN (-5550 3700) SIG_NAME M_A_DQ<43>
J 0
(-5540 3710);
DISPLAY 0.659574 (-5540 3710);
PAINT MONO (-5540 3710);
DISPLAY INVISIBLE (-5540 3710);
FORCEPROP 1 LASTPIN (-5550 3700) BN 43
J 0
(-5602 3708);
DISPLAY 0.617021 (-5602 3708);
PAINT PINK (-5602 3708);
FORCEPROP 2 LAST CDS_LIB mstr_standard
J 0
(-5600 3700);
PAINT MONO (-5600 3700);
DISPLAY INVISIBLE (-5600 3700);
FORCEPROP 1 LAST BODY_TYPE PLUMBING
J 0
(-5600 3650);
DISPLAY 1.595745 (-5600 3650);
PAINT GREEN (-5600 3650);
DISPLAY INVISIBLE (-5600 3650);
FORCEPROP 1 LAST HDL_TAP TRUE
J 0
(-5275 3575);
DISPLAY 1.595745 (-5275 3575);
PAINT GREEN (-5275 3575);
DISPLAY INVISIBLE (-5275 3575);
FORCEPROP 1 LAST PATH I65
J 0
(-5602 3700);
DISPLAY 0.872340 (-5602 3700);
PAINT GREEN (-5602 3700);
DISPLAY INVISIBLE (-5602 3700);
FORCEADD TAP..6
(-5600 3750);
FORCEPROP 3 LASTPIN (-5550 3750) SIG_NAME M_A_DQ<44>
J 0
(-5540 3760);
DISPLAY 0.659574 (-5540 3760);
PAINT MONO (-5540 3760);
DISPLAY INVISIBLE (-5540 3760);
FORCEPROP 1 LASTPIN (-5550 3750) BN 44
J 0
(-5602 3758);
DISPLAY 0.617021 (-5602 3758);
PAINT PINK (-5602 3758);
FORCEPROP 2 LAST CDS_LIB mstr_standard
J 0
(-5600 3750);
PAINT MONO (-5600 3750);
DISPLAY INVISIBLE (-5600 3750);
FORCEPROP 1 LAST BODY_TYPE PLUMBING
J 0
(-5600 3700);
DISPLAY 1.595745 (-5600 3700);
PAINT GREEN (-5600 3700);
DISPLAY INVISIBLE (-5600 3700);
FORCEPROP 1 LAST HDL_TAP TRUE
J 0
(-5275 3625);
DISPLAY 1.595745 (-5275 3625);
PAINT GREEN (-5275 3625);
DISPLAY INVISIBLE (-5275 3625);
FORCEPROP 1 LAST PATH I66
J 0
(-5602 3750);
DISPLAY 0.872340 (-5602 3750);
PAINT GREEN (-5602 3750);
DISPLAY INVISIBLE (-5602 3750);
FORCEADD TAP..6
(-5600 3800);
FORCEPROP 3 LASTPIN (-5550 3800) SIG_NAME M_A_DQ<45>
J 0
(-5540 3810);
DISPLAY 0.659574 (-5540 3810);
PAINT MONO (-5540 3810);
DISPLAY INVISIBLE (-5540 3810);
FORCEPROP 1 LASTPIN (-5550 3800) BN 45
J 0
(-5602 3808);
DISPLAY 0.617021 (-5602 3808);
PAINT PINK (-5602 3808);
FORCEPROP 2 LAST CDS_LIB mstr_standard
J 0
(-5600 3800);
PAINT MONO (-5600 3800);
DISPLAY INVISIBLE (-5600 3800);
FORCEPROP 1 LAST BODY_TYPE PLUMBING
J 0
(-5600 3750);
DISPLAY 1.595745 (-5600 3750);
PAINT GREEN (-5600 3750);
DISPLAY INVISIBLE (-5600 3750);
FORCEPROP 1 LAST HDL_TAP TRUE
J 0
(-5275 3675);
DISPLAY 1.595745 (-5275 3675);
PAINT GREEN (-5275 3675);
DISPLAY INVISIBLE (-5275 3675);
FORCEPROP 1 LAST PATH I67
J 0
(-5602 3800);
DISPLAY 0.872340 (-5602 3800);
PAINT GREEN (-5602 3800);
DISPLAY INVISIBLE (-5602 3800);
FORCEADD TAP..6
(-5600 3850);
FORCEPROP 3 LASTPIN (-5550 3850) SIG_NAME M_A_DQ<46>
J 0
(-5540 3860);
DISPLAY 0.659574 (-5540 3860);
PAINT MONO (-5540 3860);
DISPLAY INVISIBLE (-5540 3860);
FORCEPROP 1 LASTPIN (-5550 3850) BN 46
J 0
(-5602 3858);
DISPLAY 0.617021 (-5602 3858);
PAINT PINK (-5602 3858);
FORCEPROP 2 LAST CDS_LIB mstr_standard
J 0
(-5600 3850);
PAINT MONO (-5600 3850);
DISPLAY INVISIBLE (-5600 3850);
FORCEPROP 1 LAST BODY_TYPE PLUMBING
J 0
(-5600 3800);
DISPLAY 1.595745 (-5600 3800);
PAINT GREEN (-5600 3800);
DISPLAY INVISIBLE (-5600 3800);
FORCEPROP 1 LAST HDL_TAP TRUE
J 0
(-5275 3725);
DISPLAY 1.595745 (-5275 3725);
PAINT GREEN (-5275 3725);
DISPLAY INVISIBLE (-5275 3725);
FORCEPROP 1 LAST PATH I68
J 0
(-5602 3850);
DISPLAY 0.872340 (-5602 3850);
PAINT GREEN (-5602 3850);
DISPLAY INVISIBLE (-5602 3850);
FORCEADD TAP..6
(-5600 3900);
FORCEPROP 3 LASTPIN (-5550 3900) SIG_NAME M_A_DQ<47>
J 0
(-5540 3910);
DISPLAY 0.659574 (-5540 3910);
PAINT MONO (-5540 3910);
DISPLAY INVISIBLE (-5540 3910);
FORCEPROP 1 LASTPIN (-5550 3900) BN 47
J 0
(-5602 3908);
DISPLAY 0.617021 (-5602 3908);
PAINT PINK (-5602 3908);
FORCEPROP 2 LAST CDS_LIB mstr_standard
J 0
(-5600 3900);
PAINT MONO (-5600 3900);
DISPLAY INVISIBLE (-5600 3900);
FORCEPROP 1 LAST BODY_TYPE PLUMBING
J 0
(-5600 3850);
DISPLAY 1.595745 (-5600 3850);
PAINT GREEN (-5600 3850);
DISPLAY INVISIBLE (-5600 3850);
FORCEPROP 1 LAST HDL_TAP TRUE
J 0
(-5275 3775);
DISPLAY 1.595745 (-5275 3775);
PAINT GREEN (-5275 3775);
DISPLAY INVISIBLE (-5275 3775);
FORCEPROP 1 LAST PATH I69
J 0
(-5602 3900);
DISPLAY 0.872340 (-5602 3900);
PAINT GREEN (-5602 3900);
DISPLAY INVISIBLE (-5602 3900);
FORCEADD TAP..6
(-5600 800);
FORCEPROP 3 LASTPIN (-5550 800) SIG_NAME M_A_CLK_DN<3>
J 0
(-5540 810);
DISPLAY 0.659574 (-5540 810);
PAINT MONO (-5540 810);
DISPLAY INVISIBLE (-5540 810);
FORCEPROP 1 LASTPIN (-5550 800) BN 3
J 0
(-5602 808);
DISPLAY 0.617021 (-5602 808);
PAINT PINK (-5602 808);
FORCEPROP 2 LAST CDS_LIB mstr_standard
J 0
(-5600 800);
PAINT MONO (-5600 800);
DISPLAY INVISIBLE (-5600 800);
FORCEPROP 1 LAST BODY_TYPE PLUMBING
J 0
(-5600 750);
DISPLAY 1.595745 (-5600 750);
PAINT GREEN (-5600 750);
DISPLAY INVISIBLE (-5600 750);
FORCEPROP 1 LAST HDL_TAP TRUE
J 0
(-5275 675);
DISPLAY 1.595745 (-5275 675);
PAINT GREEN (-5275 675);
DISPLAY INVISIBLE (-5275 675);
FORCEPROP 1 LAST PATH I7
J 0
(-5602 800);
DISPLAY 0.872340 (-5602 800);
PAINT GREEN (-5602 800);
DISPLAY INVISIBLE (-5602 800);
FORCEADD TAP..6
(-5600 3950);
FORCEPROP 3 LASTPIN (-5550 3950) SIG_NAME M_A_DQ<48>
J 0
(-5540 3960);
DISPLAY 0.659574 (-5540 3960);
PAINT MONO (-5540 3960);
DISPLAY INVISIBLE (-5540 3960);
FORCEPROP 1 LASTPIN (-5550 3950) BN 48
J 0
(-5602 3958);
DISPLAY 0.617021 (-5602 3958);
PAINT PINK (-5602 3958);
FORCEPROP 2 LAST CDS_LIB mstr_standard
J 0
(-5600 3950);
PAINT MONO (-5600 3950);
DISPLAY INVISIBLE (-5600 3950);
FORCEPROP 1 LAST BODY_TYPE PLUMBING
J 0
(-5600 3900);
DISPLAY 1.595745 (-5600 3900);
PAINT GREEN (-5600 3900);
DISPLAY INVISIBLE (-5600 3900);
FORCEPROP 1 LAST HDL_TAP TRUE
J 0
(-5275 3825);
DISPLAY 1.595745 (-5275 3825);
PAINT GREEN (-5275 3825);
DISPLAY INVISIBLE (-5275 3825);
FORCEPROP 1 LAST PATH I70
J 0
(-5602 3950);
DISPLAY 0.872340 (-5602 3950);
PAINT GREEN (-5602 3950);
DISPLAY INVISIBLE (-5602 3950);
FORCEADD TAP..6
(-5600 4000);
FORCEPROP 3 LASTPIN (-5550 4000) SIG_NAME M_A_DQ<49>
J 0
(-5540 4010);
DISPLAY 0.659574 (-5540 4010);
PAINT MONO (-5540 4010);
DISPLAY INVISIBLE (-5540 4010);
FORCEPROP 1 LASTPIN (-5550 4000) BN 49
J 0
(-5602 4008);
DISPLAY 0.617021 (-5602 4008);
PAINT PINK (-5602 4008);
FORCEPROP 2 LAST CDS_LIB mstr_standard
J 0
(-5600 4000);
PAINT MONO (-5600 4000);
DISPLAY INVISIBLE (-5600 4000);
FORCEPROP 1 LAST BODY_TYPE PLUMBING
J 0
(-5600 3950);
DISPLAY 1.595745 (-5600 3950);
PAINT GREEN (-5600 3950);
DISPLAY INVISIBLE (-5600 3950);
FORCEPROP 1 LAST HDL_TAP TRUE
J 0
(-5275 3875);
DISPLAY 1.595745 (-5275 3875);
PAINT GREEN (-5275 3875);
DISPLAY INVISIBLE (-5275 3875);
FORCEPROP 1 LAST PATH I71
J 0
(-5602 4000);
DISPLAY 0.872340 (-5602 4000);
PAINT GREEN (-5602 4000);
DISPLAY INVISIBLE (-5602 4000);
FORCEADD OFFPAGE..6
(-6450 4825);
FORCEPROP 2 LAST $XR0 43 
J 0
(-6699 4825);
DISPLAY 0.638298 (-6699 4825);
PAINT MONO (-6699 4825);
FORCEPROP 2 LAST $XR1 44 
J 0
(-6789 4825);
DISPLAY 0.638298 (-6789 4825);
PAINT MONO (-6789 4825);
FORCEPROP 2 LAST CDS_LIB mstr_standard
J 0
(-6450 4825);
PAINT MONO (-6450 4825);
DISPLAY INVISIBLE (-6450 4825);
FORCEPROP 1 LAST OFFPAGE TRUE
J 0
(-6125 4700);
DISPLAY 1.170213 (-6125 4700);
PAINT GREEN (-6125 4700);
DISPLAY INVISIBLE (-6125 4700);
FORCEPROP 1 LAST COMMENT_BODY TRUE
J 0
(-6350 4750);
DISPLAY 1.170213 (-6350 4750);
PAINT GREEN (-6350 4750);
DISPLAY INVISIBLE (-6350 4750);
FORCEPROP 2 LAST PATH I72
J 0
(-6400 4900);
DISPLAY 1.021277 (-6400 4900);
PAINT ORANGE (-6400 4900);
DISPLAY INVISIBLE (-6400 4900);
FORCEADD TAP..6
(-5600 4050);
FORCEPROP 3 LASTPIN (-5550 4050) SIG_NAME M_A_DQ<50>
J 0
(-5540 4060);
DISPLAY 0.659574 (-5540 4060);
PAINT MONO (-5540 4060);
DISPLAY INVISIBLE (-5540 4060);
FORCEPROP 1 LASTPIN (-5550 4050) BN 50
J 0
(-5602 4058);
DISPLAY 0.617021 (-5602 4058);
PAINT PINK (-5602 4058);
FORCEPROP 2 LAST CDS_LIB mstr_standard
J 0
(-5600 4050);
PAINT MONO (-5600 4050);
DISPLAY INVISIBLE (-5600 4050);
FORCEPROP 1 LAST BODY_TYPE PLUMBING
J 0
(-5600 4000);
DISPLAY 1.595745 (-5600 4000);
PAINT GREEN (-5600 4000);
DISPLAY INVISIBLE (-5600 4000);
FORCEPROP 1 LAST HDL_TAP TRUE
J 0
(-5275 3925);
DISPLAY 1.595745 (-5275 3925);
PAINT GREEN (-5275 3925);
DISPLAY INVISIBLE (-5275 3925);
FORCEPROP 1 LAST PATH I73
J 0
(-5602 4050);
DISPLAY 0.872340 (-5602 4050);
PAINT GREEN (-5602 4050);
DISPLAY INVISIBLE (-5602 4050);
FORCEADD TAP..6
(-5600 4100);
FORCEPROP 3 LASTPIN (-5550 4100) SIG_NAME M_A_DQ<51>
J 0
(-5540 4110);
DISPLAY 0.659574 (-5540 4110);
PAINT MONO (-5540 4110);
DISPLAY INVISIBLE (-5540 4110);
FORCEPROP 1 LASTPIN (-5550 4100) BN 51
J 0
(-5602 4108);
DISPLAY 0.617021 (-5602 4108);
PAINT PINK (-5602 4108);
FORCEPROP 2 LAST CDS_LIB mstr_standard
J 0
(-5600 4100);
PAINT MONO (-5600 4100);
DISPLAY INVISIBLE (-5600 4100);
FORCEPROP 1 LAST BODY_TYPE PLUMBING
J 0
(-5600 4050);
DISPLAY 1.595745 (-5600 4050);
PAINT GREEN (-5600 4050);
DISPLAY INVISIBLE (-5600 4050);
FORCEPROP 1 LAST HDL_TAP TRUE
J 0
(-5275 3975);
DISPLAY 1.595745 (-5275 3975);
PAINT GREEN (-5275 3975);
DISPLAY INVISIBLE (-5275 3975);
FORCEPROP 1 LAST PATH I74
J 0
(-5602 4100);
DISPLAY 0.872340 (-5602 4100);
PAINT GREEN (-5602 4100);
DISPLAY INVISIBLE (-5602 4100);
FORCEADD TAP..6
(-5600 4150);
FORCEPROP 3 LASTPIN (-5550 4150) SIG_NAME M_A_DQ<52>
J 0
(-5540 4160);
DISPLAY 0.659574 (-5540 4160);
PAINT MONO (-5540 4160);
DISPLAY INVISIBLE (-5540 4160);
FORCEPROP 1 LASTPIN (-5550 4150) BN 52
J 0
(-5602 4158);
DISPLAY 0.617021 (-5602 4158);
PAINT PINK (-5602 4158);
FORCEPROP 2 LAST CDS_LIB mstr_standard
J 0
(-5600 4150);
PAINT MONO (-5600 4150);
DISPLAY INVISIBLE (-5600 4150);
FORCEPROP 1 LAST BODY_TYPE PLUMBING
J 0
(-5600 4100);
DISPLAY 1.595745 (-5600 4100);
PAINT GREEN (-5600 4100);
DISPLAY INVISIBLE (-5600 4100);
FORCEPROP 1 LAST HDL_TAP TRUE
J 0
(-5275 4025);
DISPLAY 1.595745 (-5275 4025);
PAINT GREEN (-5275 4025);
DISPLAY INVISIBLE (-5275 4025);
FORCEPROP 1 LAST PATH I75
J 0
(-5602 4150);
DISPLAY 0.872340 (-5602 4150);
PAINT GREEN (-5602 4150);
DISPLAY INVISIBLE (-5602 4150);
FORCEADD TAP..6
(-5600 4200);
FORCEPROP 3 LASTPIN (-5550 4200) SIG_NAME M_A_DQ<53>
J 0
(-5540 4210);
DISPLAY 0.659574 (-5540 4210);
PAINT MONO (-5540 4210);
DISPLAY INVISIBLE (-5540 4210);
FORCEPROP 1 LASTPIN (-5550 4200) BN 53
J 0
(-5602 4208);
DISPLAY 0.617021 (-5602 4208);
PAINT PINK (-5602 4208);
FORCEPROP 2 LAST CDS_LIB mstr_standard
J 0
(-5600 4200);
PAINT MONO (-5600 4200);
DISPLAY INVISIBLE (-5600 4200);
FORCEPROP 1 LAST BODY_TYPE PLUMBING
J 0
(-5600 4150);
DISPLAY 1.595745 (-5600 4150);
PAINT GREEN (-5600 4150);
DISPLAY INVISIBLE (-5600 4150);
FORCEPROP 1 LAST HDL_TAP TRUE
J 0
(-5275 4075);
DISPLAY 1.595745 (-5275 4075);
PAINT GREEN (-5275 4075);
DISPLAY INVISIBLE (-5275 4075);
FORCEPROP 1 LAST PATH I76
J 0
(-5602 4200);
DISPLAY 0.872340 (-5602 4200);
PAINT GREEN (-5602 4200);
DISPLAY INVISIBLE (-5602 4200);
FORCEADD TAP..6
(-5600 4250);
FORCEPROP 3 LASTPIN (-5550 4250) SIG_NAME M_A_DQ<54>
J 0
(-5540 4260);
DISPLAY 0.659574 (-5540 4260);
PAINT MONO (-5540 4260);
DISPLAY INVISIBLE (-5540 4260);
FORCEPROP 1 LASTPIN (-5550 4250) BN 54
J 0
(-5602 4258);
DISPLAY 0.617021 (-5602 4258);
PAINT PINK (-5602 4258);
FORCEPROP 2 LAST CDS_LIB mstr_standard
J 0
(-5600 4250);
PAINT MONO (-5600 4250);
DISPLAY INVISIBLE (-5600 4250);
FORCEPROP 1 LAST BODY_TYPE PLUMBING
J 0
(-5600 4200);
DISPLAY 1.595745 (-5600 4200);
PAINT GREEN (-5600 4200);
DISPLAY INVISIBLE (-5600 4200);
FORCEPROP 1 LAST HDL_TAP TRUE
J 0
(-5275 4125);
DISPLAY 1.595745 (-5275 4125);
PAINT GREEN (-5275 4125);
DISPLAY INVISIBLE (-5275 4125);
FORCEPROP 1 LAST PATH I77
J 0
(-5602 4250);
DISPLAY 0.872340 (-5602 4250);
PAINT GREEN (-5602 4250);
DISPLAY INVISIBLE (-5602 4250);
FORCEADD TAP..6
(-5600 4300);
FORCEPROP 3 LASTPIN (-5550 4300) SIG_NAME M_A_DQ<55>
J 0
(-5540 4310);
DISPLAY 0.659574 (-5540 4310);
PAINT MONO (-5540 4310);
DISPLAY INVISIBLE (-5540 4310);
FORCEPROP 1 LASTPIN (-5550 4300) BN 55
J 0
(-5602 4308);
DISPLAY 0.617021 (-5602 4308);
PAINT PINK (-5602 4308);
FORCEPROP 2 LAST CDS_LIB mstr_standard
J 0
(-5600 4300);
PAINT MONO (-5600 4300);
DISPLAY INVISIBLE (-5600 4300);
FORCEPROP 1 LAST BODY_TYPE PLUMBING
J 0
(-5600 4250);
DISPLAY 1.595745 (-5600 4250);
PAINT GREEN (-5600 4250);
DISPLAY INVISIBLE (-5600 4250);
FORCEPROP 1 LAST HDL_TAP TRUE
J 0
(-5275 4175);
DISPLAY 1.595745 (-5275 4175);
PAINT GREEN (-5275 4175);
DISPLAY INVISIBLE (-5275 4175);
FORCEPROP 1 LAST PATH I78
J 0
(-5602 4300);
DISPLAY 0.872340 (-5602 4300);
PAINT GREEN (-5602 4300);
DISPLAY INVISIBLE (-5602 4300);
FORCEADD TAP..6
(-5600 4350);
FORCEPROP 3 LASTPIN (-5550 4350) SIG_NAME M_A_DQ<56>
J 0
(-5540 4360);
DISPLAY 0.659574 (-5540 4360);
PAINT MONO (-5540 4360);
DISPLAY INVISIBLE (-5540 4360);
FORCEPROP 1 LASTPIN (-5550 4350) BN 56
J 0
(-5602 4358);
DISPLAY 0.617021 (-5602 4358);
PAINT PINK (-5602 4358);
FORCEPROP 2 LAST CDS_LIB mstr_standard
J 0
(-5600 4350);
PAINT MONO (-5600 4350);
DISPLAY INVISIBLE (-5600 4350);
FORCEPROP 1 LAST BODY_TYPE PLUMBING
J 0
(-5600 4300);
DISPLAY 1.595745 (-5600 4300);
PAINT GREEN (-5600 4300);
DISPLAY INVISIBLE (-5600 4300);
FORCEPROP 1 LAST HDL_TAP TRUE
J 0
(-5275 4225);
DISPLAY 1.595745 (-5275 4225);
PAINT GREEN (-5275 4225);
DISPLAY INVISIBLE (-5275 4225);
FORCEPROP 1 LAST PATH I79
J 0
(-5602 4350);
DISPLAY 0.872340 (-5602 4350);
PAINT GREEN (-5602 4350);
DISPLAY INVISIBLE (-5602 4350);
FORCEADD TAP..6
(-5600 750);
FORCEPROP 3 LASTPIN (-5550 750) SIG_NAME M_A_CLK_DN<2>
J 0
(-5540 760);
DISPLAY 0.659574 (-5540 760);
PAINT MONO (-5540 760);
DISPLAY INVISIBLE (-5540 760);
FORCEPROP 1 LASTPIN (-5550 750) BN 2
J 0
(-5602 758);
DISPLAY 0.617021 (-5602 758);
PAINT PINK (-5602 758);
FORCEPROP 2 LAST CDS_LIB mstr_standard
J 0
(-5600 750);
PAINT MONO (-5600 750);
DISPLAY INVISIBLE (-5600 750);
FORCEPROP 1 LAST BODY_TYPE PLUMBING
J 0
(-5600 700);
DISPLAY 1.595745 (-5600 700);
PAINT GREEN (-5600 700);
DISPLAY INVISIBLE (-5600 700);
FORCEPROP 1 LAST HDL_TAP TRUE
J 0
(-5275 625);
DISPLAY 1.595745 (-5275 625);
PAINT GREEN (-5275 625);
DISPLAY INVISIBLE (-5275 625);
FORCEPROP 1 LAST PATH I8
J 0
(-5602 750);
DISPLAY 0.872340 (-5602 750);
PAINT GREEN (-5602 750);
DISPLAY INVISIBLE (-5602 750);
FORCEADD TAP..6
(-5600 4400);
FORCEPROP 3 LASTPIN (-5550 4400) SIG_NAME M_A_DQ<57>
J 0
(-5540 4410);
DISPLAY 0.659574 (-5540 4410);
PAINT MONO (-5540 4410);
DISPLAY INVISIBLE (-5540 4410);
FORCEPROP 1 LASTPIN (-5550 4400) BN 57
J 0
(-5602 4408);
DISPLAY 0.617021 (-5602 4408);
PAINT PINK (-5602 4408);
FORCEPROP 2 LAST CDS_LIB mstr_standard
J 0
(-5600 4400);
PAINT MONO (-5600 4400);
DISPLAY INVISIBLE (-5600 4400);
FORCEPROP 1 LAST BODY_TYPE PLUMBING
J 0
(-5600 4350);
DISPLAY 1.595745 (-5600 4350);
PAINT GREEN (-5600 4350);
DISPLAY INVISIBLE (-5600 4350);
FORCEPROP 1 LAST HDL_TAP TRUE
J 0
(-5275 4275);
DISPLAY 1.595745 (-5275 4275);
PAINT GREEN (-5275 4275);
DISPLAY INVISIBLE (-5275 4275);
FORCEPROP 1 LAST PATH I80
J 0
(-5602 4400);
DISPLAY 0.872340 (-5602 4400);
PAINT GREEN (-5602 4400);
DISPLAY INVISIBLE (-5602 4400);
FORCEADD TAP..6
(-5600 4450);
FORCEPROP 3 LASTPIN (-5550 4450) SIG_NAME M_A_DQ<58>
J 0
(-5540 4460);
DISPLAY 0.659574 (-5540 4460);
PAINT MONO (-5540 4460);
DISPLAY INVISIBLE (-5540 4460);
FORCEPROP 1 LASTPIN (-5550 4450) BN 58
J 0
(-5602 4458);
DISPLAY 0.617021 (-5602 4458);
PAINT PINK (-5602 4458);
FORCEPROP 2 LAST CDS_LIB mstr_standard
J 0
(-5600 4450);
PAINT MONO (-5600 4450);
DISPLAY INVISIBLE (-5600 4450);
FORCEPROP 1 LAST BODY_TYPE PLUMBING
J 0
(-5600 4400);
DISPLAY 1.595745 (-5600 4400);
PAINT GREEN (-5600 4400);
DISPLAY INVISIBLE (-5600 4400);
FORCEPROP 1 LAST HDL_TAP TRUE
J 0
(-5275 4325);
DISPLAY 1.595745 (-5275 4325);
PAINT GREEN (-5275 4325);
DISPLAY INVISIBLE (-5275 4325);
FORCEPROP 1 LAST PATH I81
J 0
(-5602 4450);
DISPLAY 0.872340 (-5602 4450);
PAINT GREEN (-5602 4450);
DISPLAY INVISIBLE (-5602 4450);
FORCEADD TAP..6
(-5600 4500);
FORCEPROP 3 LASTPIN (-5550 4500) SIG_NAME M_A_DQ<59>
J 0
(-5540 4510);
DISPLAY 0.659574 (-5540 4510);
PAINT MONO (-5540 4510);
DISPLAY INVISIBLE (-5540 4510);
FORCEPROP 1 LASTPIN (-5550 4500) BN 59
J 0
(-5602 4508);
DISPLAY 0.617021 (-5602 4508);
PAINT PINK (-5602 4508);
FORCEPROP 2 LAST CDS_LIB mstr_standard
J 0
(-5600 4500);
PAINT MONO (-5600 4500);
DISPLAY INVISIBLE (-5600 4500);
FORCEPROP 1 LAST BODY_TYPE PLUMBING
J 0
(-5600 4450);
DISPLAY 1.595745 (-5600 4450);
PAINT GREEN (-5600 4450);
DISPLAY INVISIBLE (-5600 4450);
FORCEPROP 1 LAST HDL_TAP TRUE
J 0
(-5275 4375);
DISPLAY 1.595745 (-5275 4375);
PAINT GREEN (-5275 4375);
DISPLAY INVISIBLE (-5275 4375);
FORCEPROP 1 LAST PATH I82
J 0
(-5602 4500);
DISPLAY 0.872340 (-5602 4500);
PAINT GREEN (-5602 4500);
DISPLAY INVISIBLE (-5602 4500);
FORCEADD TAP..6
(-5600 4550);
FORCEPROP 3 LASTPIN (-5550 4550) SIG_NAME M_A_DQ<60>
J 0
(-5540 4560);
DISPLAY 0.659574 (-5540 4560);
PAINT MONO (-5540 4560);
DISPLAY INVISIBLE (-5540 4560);
FORCEPROP 1 LASTPIN (-5550 4550) BN 60
J 0
(-5602 4558);
DISPLAY 0.617021 (-5602 4558);
PAINT PINK (-5602 4558);
FORCEPROP 2 LAST CDS_LIB mstr_standard
J 0
(-5600 4550);
PAINT MONO (-5600 4550);
DISPLAY INVISIBLE (-5600 4550);
FORCEPROP 1 LAST BODY_TYPE PLUMBING
J 0
(-5600 4500);
DISPLAY 1.595745 (-5600 4500);
PAINT GREEN (-5600 4500);
DISPLAY INVISIBLE (-5600 4500);
FORCEPROP 1 LAST HDL_TAP TRUE
J 0
(-5275 4425);
DISPLAY 1.595745 (-5275 4425);
PAINT GREEN (-5275 4425);
DISPLAY INVISIBLE (-5275 4425);
FORCEPROP 1 LAST PATH I83
J 0
(-5602 4550);
DISPLAY 0.872340 (-5602 4550);
PAINT GREEN (-5602 4550);
DISPLAY INVISIBLE (-5602 4550);
FORCEADD TAP..6
(-5600 4600);
FORCEPROP 3 LASTPIN (-5550 4600) SIG_NAME M_A_DQ<61>
J 0
(-5540 4610);
DISPLAY 0.659574 (-5540 4610);
PAINT MONO (-5540 4610);
DISPLAY INVISIBLE (-5540 4610);
FORCEPROP 1 LASTPIN (-5550 4600) BN 61
J 0
(-5602 4608);
DISPLAY 0.617021 (-5602 4608);
PAINT PINK (-5602 4608);
FORCEPROP 2 LAST CDS_LIB mstr_standard
J 0
(-5600 4600);
PAINT MONO (-5600 4600);
DISPLAY INVISIBLE (-5600 4600);
FORCEPROP 1 LAST BODY_TYPE PLUMBING
J 0
(-5600 4550);
DISPLAY 1.595745 (-5600 4550);
PAINT GREEN (-5600 4550);
DISPLAY INVISIBLE (-5600 4550);
FORCEPROP 1 LAST HDL_TAP TRUE
J 0
(-5275 4475);
DISPLAY 1.595745 (-5275 4475);
PAINT GREEN (-5275 4475);
DISPLAY INVISIBLE (-5275 4475);
FORCEPROP 1 LAST PATH I84
J 0
(-5602 4600);
DISPLAY 0.872340 (-5602 4600);
PAINT GREEN (-5602 4600);
DISPLAY INVISIBLE (-5602 4600);
FORCEADD TAP..6
(-5600 4650);
FORCEPROP 3 LASTPIN (-5550 4650) SIG_NAME M_A_DQ<62>
J 0
(-5540 4660);
DISPLAY 0.659574 (-5540 4660);
PAINT MONO (-5540 4660);
DISPLAY INVISIBLE (-5540 4660);
FORCEPROP 1 LASTPIN (-5550 4650) BN 62
J 0
(-5602 4658);
DISPLAY 0.617021 (-5602 4658);
PAINT PINK (-5602 4658);
FORCEPROP 2 LAST CDS_LIB mstr_standard
J 0
(-5600 4650);
PAINT MONO (-5600 4650);
DISPLAY INVISIBLE (-5600 4650);
FORCEPROP 1 LAST BODY_TYPE PLUMBING
J 0
(-5600 4600);
DISPLAY 1.595745 (-5600 4600);
PAINT GREEN (-5600 4600);
DISPLAY INVISIBLE (-5600 4600);
FORCEPROP 1 LAST HDL_TAP TRUE
J 0
(-5275 4525);
DISPLAY 1.595745 (-5275 4525);
PAINT GREEN (-5275 4525);
DISPLAY INVISIBLE (-5275 4525);
FORCEPROP 1 LAST PATH I85
J 0
(-5602 4650);
DISPLAY 0.872340 (-5602 4650);
PAINT GREEN (-5602 4650);
DISPLAY INVISIBLE (-5602 4650);
FORCEADD TAP..6
(-5600 4700);
FORCEPROP 3 LASTPIN (-5550 4700) SIG_NAME M_A_DQ<63>
J 0
(-5540 4710);
DISPLAY 0.659574 (-5540 4710);
PAINT MONO (-5540 4710);
DISPLAY INVISIBLE (-5540 4710);
FORCEPROP 1 LASTPIN (-5550 4700) BN 63
J 0
(-5602 4708);
DISPLAY 0.617021 (-5602 4708);
PAINT PINK (-5602 4708);
FORCEPROP 2 LAST CDS_LIB mstr_standard
J 0
(-5600 4700);
PAINT MONO (-5600 4700);
DISPLAY INVISIBLE (-5600 4700);
FORCEPROP 1 LAST BODY_TYPE PLUMBING
J 0
(-5600 4650);
DISPLAY 1.595745 (-5600 4650);
PAINT GREEN (-5600 4650);
DISPLAY INVISIBLE (-5600 4650);
FORCEPROP 1 LAST HDL_TAP TRUE
J 0
(-5275 4575);
DISPLAY 1.595745 (-5275 4575);
PAINT GREEN (-5275 4575);
DISPLAY INVISIBLE (-5275 4575);
FORCEPROP 1 LAST PATH I86
J 0
(-5602 4700);
DISPLAY 0.872340 (-5602 4700);
PAINT GREEN (-5602 4700);
DISPLAY INVISIBLE (-5602 4700);
FORCEADD TAP..6
R 2
(-2875 800);
FORCEPROP 3 LASTPIN (-2925 800) SIG_NAME M_A_BA<1>
J 0
(-2915 810);
DISPLAY 0.659574 (-2915 810);
PAINT MONO (-2915 810);
DISPLAY INVISIBLE (-2915 810);
FORCEPROP 1 LASTPIN (-2925 800) BN 1
J 2
(-2873 808);
DISPLAY 0.617021 (-2873 808);
PAINT PINK (-2873 808);
FORCEPROP 2 LAST CDS_LIB mstr_standard
J 0
(-2875 800);
PAINT MONO (-2875 800);
DISPLAY INVISIBLE (-2875 800);
FORCEPROP 1 LAST BODY_TYPE PLUMBING
J 2
(-2875 750);
DISPLAY 1.595745 (-2875 750);
PAINT GREEN (-2875 750);
DISPLAY INVISIBLE (-2875 750);
FORCEPROP 1 LAST HDL_TAP TRUE
J 2
(-3200 675);
DISPLAY 1.595745 (-3200 675);
PAINT GREEN (-3200 675);
DISPLAY INVISIBLE (-3200 675);
FORCEPROP 1 LAST PATH I87
J 2
(-2873 800);
DISPLAY 0.872340 (-2873 800);
PAINT GREEN (-2873 800);
DISPLAY INVISIBLE (-2873 800);
FORCEADD TAP..6
R 2
(-2875 750);
FORCEPROP 3 LASTPIN (-2925 750) SIG_NAME M_A_BA<0>
J 0
(-2915 760);
DISPLAY 0.659574 (-2915 760);
PAINT MONO (-2915 760);
DISPLAY INVISIBLE (-2915 760);
FORCEPROP 1 LASTPIN (-2925 750) BN 0
J 2
(-2873 758);
DISPLAY 0.617021 (-2873 758);
PAINT PINK (-2873 758);
FORCEPROP 2 LAST CDS_LIB mstr_standard
J 0
(-2875 750);
PAINT MONO (-2875 750);
DISPLAY INVISIBLE (-2875 750);
FORCEPROP 1 LAST BODY_TYPE PLUMBING
J 2
(-2875 700);
DISPLAY 1.595745 (-2875 700);
PAINT GREEN (-2875 700);
DISPLAY INVISIBLE (-2875 700);
FORCEPROP 1 LAST HDL_TAP TRUE
J 2
(-3200 625);
DISPLAY 1.595745 (-3200 625);
PAINT GREEN (-3200 625);
DISPLAY INVISIBLE (-3200 625);
FORCEPROP 1 LAST PATH I88
J 2
(-2873 750);
DISPLAY 0.872340 (-2873 750);
PAINT GREEN (-2873 750);
DISPLAY INVISIBLE (-2873 750);
FORCEADD TAP..6
R 2
(-2875 900);
FORCEPROP 3 LASTPIN (-2925 900) SIG_NAME M_A_BG<1>
J 0
(-2915 910);
DISPLAY 0.659574 (-2915 910);
PAINT MONO (-2915 910);
DISPLAY INVISIBLE (-2915 910);
FORCEPROP 1 LASTPIN (-2925 900) BN 1
J 2
(-2873 908);
DISPLAY 0.617021 (-2873 908);
PAINT PINK (-2873 908);
FORCEPROP 2 LAST CDS_LIB mstr_standard
J 0
(-2875 900);
PAINT MONO (-2875 900);
DISPLAY INVISIBLE (-2875 900);
FORCEPROP 1 LAST BODY_TYPE PLUMBING
J 2
(-2875 850);
DISPLAY 1.595745 (-2875 850);
PAINT GREEN (-2875 850);
DISPLAY INVISIBLE (-2875 850);
FORCEPROP 1 LAST HDL_TAP TRUE
J 2
(-3200 775);
DISPLAY 1.595745 (-3200 775);
PAINT GREEN (-3200 775);
DISPLAY INVISIBLE (-3200 775);
FORCEPROP 1 LAST PATH I89
J 2
(-2873 900);
DISPLAY 0.872340 (-2873 900);
PAINT GREEN (-2873 900);
DISPLAY INVISIBLE (-2873 900);
FORCEADD TAP..6
(-5600 900);
FORCEPROP 3 LASTPIN (-5550 900) SIG_NAME M_A_CLK_DP<1>
J 0
(-5540 910);
DISPLAY 0.659574 (-5540 910);
PAINT MONO (-5540 910);
DISPLAY INVISIBLE (-5540 910);
FORCEPROP 1 LASTPIN (-5550 900) BN 1
J 0
(-5602 908);
DISPLAY 0.617021 (-5602 908);
PAINT PINK (-5602 908);
FORCEPROP 2 LAST CDS_LIB mstr_standard
J 0
(-5600 900);
PAINT MONO (-5600 900);
DISPLAY INVISIBLE (-5600 900);
FORCEPROP 1 LAST BODY_TYPE PLUMBING
J 0
(-5600 850);
DISPLAY 1.595745 (-5600 850);
PAINT GREEN (-5600 850);
DISPLAY INVISIBLE (-5600 850);
FORCEPROP 1 LAST HDL_TAP TRUE
J 0
(-5275 775);
DISPLAY 1.595745 (-5275 775);
PAINT GREEN (-5275 775);
DISPLAY INVISIBLE (-5275 775);
FORCEPROP 1 LAST PATH I9
J 0
(-5602 900);
DISPLAY 0.872340 (-5602 900);
PAINT GREEN (-5602 900);
DISPLAY INVISIBLE (-5602 900);
FORCEADD TAP..6
R 2
(-2875 850);
FORCEPROP 3 LASTPIN (-2925 850) SIG_NAME M_A_BG<0>
J 0
(-2915 860);
DISPLAY 0.659574 (-2915 860);
PAINT MONO (-2915 860);
DISPLAY INVISIBLE (-2915 860);
FORCEPROP 1 LASTPIN (-2925 850) BN 0
J 2
(-2873 858);
DISPLAY 0.617021 (-2873 858);
PAINT PINK (-2873 858);
FORCEPROP 2 LAST CDS_LIB mstr_standard
J 0
(-2875 850);
PAINT MONO (-2875 850);
DISPLAY INVISIBLE (-2875 850);
FORCEPROP 1 LAST BODY_TYPE PLUMBING
J 2
(-2875 800);
DISPLAY 1.595745 (-2875 800);
PAINT GREEN (-2875 800);
DISPLAY INVISIBLE (-2875 800);
FORCEPROP 1 LAST HDL_TAP TRUE
J 2
(-3200 725);
DISPLAY 1.595745 (-3200 725);
PAINT GREEN (-3200 725);
DISPLAY INVISIBLE (-3200 725);
FORCEPROP 1 LAST PATH I90
J 2
(-2873 850);
DISPLAY 0.872340 (-2873 850);
PAINT GREEN (-2873 850);
DISPLAY INVISIBLE (-2873 850);
FORCEADD TAP..6
R 2
(-2875 1150);
FORCEPROP 3 LASTPIN (-2925 1150) SIG_NAME M_A_CS_N<3>
J 0
(-2915 1160);
DISPLAY 0.659574 (-2915 1160);
PAINT MONO (-2915 1160);
DISPLAY INVISIBLE (-2915 1160);
FORCEPROP 1 LASTPIN (-2925 1150) BN 3
J 2
(-2873 1158);
DISPLAY 0.617021 (-2873 1158);
PAINT PINK (-2873 1158);
FORCEPROP 2 LAST CDS_LIB mstr_standard
J 0
(-2875 1150);
PAINT MONO (-2875 1150);
DISPLAY INVISIBLE (-2875 1150);
FORCEPROP 1 LAST BODY_TYPE PLUMBING
J 2
(-2875 1100);
DISPLAY 1.595745 (-2875 1100);
PAINT GREEN (-2875 1100);
DISPLAY INVISIBLE (-2875 1100);
FORCEPROP 1 LAST HDL_TAP TRUE
J 2
(-3200 1025);
DISPLAY 1.595745 (-3200 1025);
PAINT GREEN (-3200 1025);
DISPLAY INVISIBLE (-3200 1025);
FORCEPROP 1 LAST PATH I91
J 2
(-2873 1150);
DISPLAY 0.872340 (-2873 1150);
PAINT GREEN (-2873 1150);
DISPLAY INVISIBLE (-2873 1150);
FORCEADD TAP..6
R 2
(-2875 1200);
FORCEPROP 3 LASTPIN (-2925 1200) SIG_NAME M_A_CS_N<4>
J 0
(-2915 1210);
DISPLAY 0.659574 (-2915 1210);
PAINT MONO (-2915 1210);
DISPLAY INVISIBLE (-2915 1210);
FORCEPROP 1 LASTPIN (-2925 1200) BN 4
J 2
(-2873 1208);
DISPLAY 0.617021 (-2873 1208);
PAINT PINK (-2873 1208);
FORCEPROP 2 LAST CDS_LIB mstr_standard
J 0
(-2875 1200);
PAINT MONO (-2875 1200);
DISPLAY INVISIBLE (-2875 1200);
FORCEPROP 1 LAST BODY_TYPE PLUMBING
J 2
(-2875 1150);
DISPLAY 1.595745 (-2875 1150);
PAINT GREEN (-2875 1150);
DISPLAY INVISIBLE (-2875 1150);
FORCEPROP 1 LAST HDL_TAP TRUE
J 2
(-3200 1075);
DISPLAY 1.595745 (-3200 1075);
PAINT GREEN (-3200 1075);
DISPLAY INVISIBLE (-3200 1075);
FORCEPROP 1 LAST PATH I92
J 2
(-2873 1200);
DISPLAY 0.872340 (-2873 1200);
PAINT GREEN (-2873 1200);
DISPLAY INVISIBLE (-2873 1200);
FORCEADD TAP..6
R 2
(-2875 1100);
FORCEPROP 3 LASTPIN (-2925 1100) SIG_NAME M_A_CS_N<2>
J 0
(-2915 1110);
DISPLAY 0.659574 (-2915 1110);
PAINT MONO (-2915 1110);
DISPLAY INVISIBLE (-2915 1110);
FORCEPROP 1 LASTPIN (-2925 1100) BN 2
J 2
(-2873 1108);
DISPLAY 0.617021 (-2873 1108);
PAINT PINK (-2873 1108);
FORCEPROP 2 LAST CDS_LIB mstr_standard
J 0
(-2875 1100);
PAINT MONO (-2875 1100);
DISPLAY INVISIBLE (-2875 1100);
FORCEPROP 1 LAST BODY_TYPE PLUMBING
J 2
(-2875 1050);
DISPLAY 1.595745 (-2875 1050);
PAINT GREEN (-2875 1050);
DISPLAY INVISIBLE (-2875 1050);
FORCEPROP 1 LAST HDL_TAP TRUE
J 2
(-3200 975);
DISPLAY 1.595745 (-3200 975);
PAINT GREEN (-3200 975);
DISPLAY INVISIBLE (-3200 975);
FORCEPROP 1 LAST PATH I93
J 2
(-2873 1100);
DISPLAY 0.872340 (-2873 1100);
PAINT GREEN (-2873 1100);
DISPLAY INVISIBLE (-2873 1100);
FORCEADD TAP..6
R 2
(-2875 1050);
FORCEPROP 3 LASTPIN (-2925 1050) SIG_NAME M_A_CS_N<1>
J 0
(-2915 1060);
DISPLAY 0.659574 (-2915 1060);
PAINT MONO (-2915 1060);
DISPLAY INVISIBLE (-2915 1060);
FORCEPROP 1 LASTPIN (-2925 1050) BN 1
J 2
(-2873 1058);
DISPLAY 0.617021 (-2873 1058);
PAINT PINK (-2873 1058);
FORCEPROP 2 LAST CDS_LIB mstr_standard
J 0
(-2875 1050);
PAINT MONO (-2875 1050);
DISPLAY INVISIBLE (-2875 1050);
FORCEPROP 1 LAST BODY_TYPE PLUMBING
J 2
(-2875 1000);
DISPLAY 1.595745 (-2875 1000);
PAINT GREEN (-2875 1000);
DISPLAY INVISIBLE (-2875 1000);
FORCEPROP 1 LAST HDL_TAP TRUE
J 2
(-3200 925);
DISPLAY 1.595745 (-3200 925);
PAINT GREEN (-3200 925);
DISPLAY INVISIBLE (-3200 925);
FORCEPROP 1 LAST PATH I94
J 2
(-2873 1050);
DISPLAY 0.872340 (-2873 1050);
PAINT GREEN (-2873 1050);
DISPLAY INVISIBLE (-2873 1050);
FORCEADD TAP..6
R 2
(-2875 1000);
FORCEPROP 3 LASTPIN (-2925 1000) SIG_NAME M_A_CS_N<0>
J 0
(-2915 1010);
DISPLAY 0.659574 (-2915 1010);
PAINT MONO (-2915 1010);
DISPLAY INVISIBLE (-2915 1010);
FORCEPROP 1 LASTPIN (-2925 1000) BN 0
J 2
(-2873 1008);
DISPLAY 0.617021 (-2873 1008);
PAINT PINK (-2873 1008);
FORCEPROP 2 LAST CDS_LIB mstr_standard
J 0
(-2875 1000);
PAINT MONO (-2875 1000);
DISPLAY INVISIBLE (-2875 1000);
FORCEPROP 1 LAST BODY_TYPE PLUMBING
J 2
(-2875 950);
DISPLAY 1.595745 (-2875 950);
PAINT GREEN (-2875 950);
DISPLAY INVISIBLE (-2875 950);
FORCEPROP 1 LAST HDL_TAP TRUE
J 2
(-3200 875);
DISPLAY 1.595745 (-3200 875);
PAINT GREEN (-3200 875);
DISPLAY INVISIBLE (-3200 875);
FORCEPROP 1 LAST PATH I95
J 2
(-2873 1000);
DISPLAY 0.872340 (-2873 1000);
PAINT GREEN (-2873 1000);
DISPLAY INVISIBLE (-2873 1000);
FORCEADD TAP..6
R 2
(-2875 1300);
FORCEPROP 3 LASTPIN (-2925 1300) SIG_NAME M_A_CS_N<6>
J 0
(-2915 1310);
DISPLAY 0.659574 (-2915 1310);
PAINT MONO (-2915 1310);
DISPLAY INVISIBLE (-2915 1310);
FORCEPROP 1 LASTPIN (-2925 1300) BN 6
J 2
(-2873 1308);
DISPLAY 0.617021 (-2873 1308);
PAINT PINK (-2873 1308);
FORCEPROP 2 LAST CDS_LIB mstr_standard
J 0
(-2875 1300);
PAINT MONO (-2875 1300);
DISPLAY INVISIBLE (-2875 1300);
FORCEPROP 1 LAST BODY_TYPE PLUMBING
J 2
(-2875 1250);
DISPLAY 1.595745 (-2875 1250);
PAINT GREEN (-2875 1250);
DISPLAY INVISIBLE (-2875 1250);
FORCEPROP 1 LAST HDL_TAP TRUE
J 2
(-3200 1175);
DISPLAY 1.595745 (-3200 1175);
PAINT GREEN (-3200 1175);
DISPLAY INVISIBLE (-3200 1175);
FORCEPROP 1 LAST PATH I96
J 2
(-2873 1300);
DISPLAY 0.872340 (-2873 1300);
PAINT GREEN (-2873 1300);
DISPLAY INVISIBLE (-2873 1300);
FORCEADD TAP..6
R 2
(-2875 1350);
FORCEPROP 3 LASTPIN (-2925 1350) SIG_NAME M_A_CS_N<7>
J 0
(-2915 1360);
DISPLAY 0.659574 (-2915 1360);
PAINT MONO (-2915 1360);
DISPLAY INVISIBLE (-2915 1360);
FORCEPROP 1 LASTPIN (-2925 1350) BN 7
J 2
(-2873 1358);
DISPLAY 0.617021 (-2873 1358);
PAINT PINK (-2873 1358);
FORCEPROP 2 LAST CDS_LIB mstr_standard
J 0
(-2875 1350);
PAINT MONO (-2875 1350);
DISPLAY INVISIBLE (-2875 1350);
FORCEPROP 1 LAST BODY_TYPE PLUMBING
J 2
(-2875 1300);
DISPLAY 1.595745 (-2875 1300);
PAINT GREEN (-2875 1300);
DISPLAY INVISIBLE (-2875 1300);
FORCEPROP 1 LAST HDL_TAP TRUE
J 2
(-3200 1225);
DISPLAY 1.595745 (-3200 1225);
PAINT GREEN (-3200 1225);
DISPLAY INVISIBLE (-3200 1225);
FORCEPROP 1 LAST PATH I97
J 2
(-2873 1350);
DISPLAY 0.872340 (-2873 1350);
PAINT GREEN (-2873 1350);
DISPLAY INVISIBLE (-2873 1350);
FORCEADD TAP..6
R 2
(-2875 1250);
FORCEPROP 3 LASTPIN (-2925 1250) SIG_NAME M_A_CS_N<5>
J 0
(-2915 1260);
DISPLAY 0.659574 (-2915 1260);
PAINT MONO (-2915 1260);
DISPLAY INVISIBLE (-2915 1260);
FORCEPROP 1 LASTPIN (-2925 1250) BN 5
J 2
(-2873 1258);
DISPLAY 0.617021 (-2873 1258);
PAINT PINK (-2873 1258);
FORCEPROP 2 LAST CDS_LIB mstr_standard
J 0
(-2875 1250);
PAINT MONO (-2875 1250);
DISPLAY INVISIBLE (-2875 1250);
FORCEPROP 1 LAST BODY_TYPE PLUMBING
J 2
(-2875 1200);
DISPLAY 1.595745 (-2875 1200);
PAINT GREEN (-2875 1200);
DISPLAY INVISIBLE (-2875 1200);
FORCEPROP 1 LAST HDL_TAP TRUE
J 2
(-3200 1125);
DISPLAY 1.595745 (-3200 1125);
PAINT GREEN (-3200 1125);
DISPLAY INVISIBLE (-3200 1125);
FORCEPROP 1 LAST PATH I98
J 2
(-2873 1250);
DISPLAY 0.872340 (-2873 1250);
PAINT GREEN (-2873 1250);
DISPLAY INVISIBLE (-2873 1250);
FORCEADD TAP..6
R 2
(-2875 1450);
FORCEPROP 3 LASTPIN (-2925 1450) SIG_NAME M_A_ODT<0>
J 0
(-2915 1460);
DISPLAY 0.659574 (-2915 1460);
PAINT MONO (-2915 1460);
DISPLAY INVISIBLE (-2915 1460);
FORCEPROP 1 LASTPIN (-2925 1450) BN 0
J 2
(-2873 1458);
DISPLAY 0.617021 (-2873 1458);
PAINT PINK (-2873 1458);
FORCEPROP 2 LAST CDS_LIB mstr_standard
J 0
(-2875 1450);
PAINT MONO (-2875 1450);
DISPLAY INVISIBLE (-2875 1450);
FORCEPROP 1 LAST BODY_TYPE PLUMBING
J 2
(-2875 1400);
DISPLAY 1.595745 (-2875 1400);
PAINT GREEN (-2875 1400);
DISPLAY INVISIBLE (-2875 1400);
FORCEPROP 1 LAST HDL_TAP TRUE
J 2
(-3200 1325);
DISPLAY 1.595745 (-3200 1325);
PAINT GREEN (-3200 1325);
DISPLAY INVISIBLE (-3200 1325);
FORCEPROP 1 LAST PATH I99
J 2
(-2873 1450);
DISPLAY 0.872340 (-2873 1450);
PAINT GREEN (-2873 1450);
DISPLAY INVISIBLE (-2873 1450);
FORCEADD DESIGN_NOTE..1
(-6300 425);
FORCEPROP 0 LAST L1 CPU SYMBOLS 1-30 ARE PRELIMINARY AND SUBJECT TO CHANGE
J 0
(-6500 300);
DISPLAY 1.021277 (-6500 300);
PAINT ORANGE (-6500 300);
FORCEPROP 2 LAST CDS_LIB mstr_symbols
J 0
(-6300 425);
PAINT ORANGE (-6300 425);
DISPLAY INVISIBLE (-6300 425);
FORCEPROP 1 LAST COMMENT_BODY TRUE
J 0
(-6275 525);
DISPLAY 0.978723 (-6275 525);
PAINT ORANGE (-6275 525);
DISPLAY INVISIBLE (-6275 525);
FORCEADD PRELIM..10
(-4240 2590);
PAINT GRAY (-4240 2590);
FORCEPROP 2 LAST CDS_LIB mstr_misc
J 0
(-4240 2590);
PAINT ORANGE (-4240 2590);
DISPLAY INVISIBLE (-4240 2590);
FORCEPROP 1 LAST COMMENT_BODY TRUE
J 0
(-4240 2590);
PAINT ORANGE (-4240 2590);
DISPLAY INVISIBLE (-4240 2590);
FORCEADD INTEL_CORP_BPAGE..1
(0 0);
FORCEPROP 1 LAST CDS_CON_LAST_MODIFIED Tue Dec 01 11:51:16 2015
J 0
(-1425 325);
DISPLAY 1.340426 (-1425 325);
PAINT GREEN (-1425 325);
DISPLAY INVISIBLE (-1425 325);
FORCEPROP 1 LAST CUSTOM_TXT_CDS <CURRENT_DESIGN_SHEET> OF <TOTAL_DESIGN_SHEETS>
J 0
(-500 25);
PAINT GREEN (-500 25);
FORCEPROP 1 LAST CUSTOM_TXT_CDS <CON_LAST_MODIFIED>
J 0
(-1925 350);
PAINT GREEN (-1925 350);
FORCEPROP 2 LAST CUSTOM_TXT_CDS <XR_PAGE_TITLE>
J 0
(-7890 5250);
DISPLAY 0.638298 (-7890 5250);
PAINT PINK (-7890 5250);
DISPLAY INVISIBLE (-7890 5250);
FORCEPROP 1 LAST SCH_ADDRESS3 Santa Clara, CA 95052-8119
J 0
(-3975 25);
DISPLAY 0.617021 (-3975 25);
PAINT GREEN (-3975 25);
FORCEPROP 1 LAST SCH_ADDRESS2 P.O. BOX 58119
J 0
(-3975 75);
DISPLAY 0.617021 (-3975 75);
PAINT GREEN (-3975 75);
FORCEPROP 1 LAST SCH_ADDRESS1 2200 Mission College Blvd.
J 0
(-3975 125);
DISPLAY 0.617021 (-3975 125);
PAINT GREEN (-3975 125);
FORCEPROP 1 LAST SCH_TITLE SKYLAKE - SKT0 - 3 OF 21
J 0
(-7950 50);
DISPLAY 1.212766 (-7950 50);
PAINT GREEN (-7950 50);
FORCEPROP 1 LAST SCH_NUMBER H4694802
J 0
(-1300 150);
DISPLAY 1.212766 (-1300 150);
PAINT YELLOW (-1300 150);
FORCEPROP 1 LAST SCH_DEPT BESD
J 1
(-4450 100);
DISPLAY 1.212766 (-4450 100);
PAINT YELLOW (-4450 100);
FORCEPROP 1 LAST SCH_REV 2.420
J 0
(-250 150);
DISPLAY 0.978723 (-250 150);
PAINT YELLOW (-250 150);
FORCEPROP 2 LAST CDS_LIB mstr_symbols
J 0
(0 0);
PAINT ORANGE (0 0);
DISPLAY INVISIBLE (0 0);
FORCEPROP 2 LAST PAGE_BORDER TRUE
J 0
(-7890 5250);
DISPLAY 0.851064 (-7890 5250);
PAINT PINK (-7890 5250);
DISPLAY INVISIBLE (-7890 5250);
FORCEPROP 1 LAST COMMENT_BODY TRUE
J 0
(12 12);
DISPLAY 0.638298 (12 12);
PAINT GREEN (12 12);
DISPLAY INVISIBLE (12 12);
FORCEPROP 2 LAST CDS_XR_PAGE_TITLE CR-23 : @BASEBOARD_FAB2_LIB.BASEBOARD_FAB2(SCH_1):PAGE23
J 0
(-7890 5250);
DISPLAY 0.638298 (-7890 5250);
PAINT PINK (-7890 5250);
DISPLAY INVISIBLE (-7890 5250);
WIRE 17 -1 (-5650 1725)(-5650 1775);
WIRE 17 -1 (-5650 1675)(-5650 1725);
WIRE 17 -1 (-5650 1775)(-5650 1825);
WIRE 17 -1 (-5650 1825)(-5650 1875);
WIRE 17 -1 (-5650 1625)(-5650 1675);
WIRE 17 -1 (-5650 1575)(-5650 1625);
WIRE 17 -1 (-5650 1875)(-5650 1925);
WIRE 17 -1 (-5650 1925)(-5650 1975);
WIRE 17 -1 (-5650 1975)(-5650 2025);
WIRE 17 -1 (-5650 2025)(-5650 2075);
WIRE 17 -1 (-5650 2075)(-5650 2125);
WIRE 17 -1 (-5650 2125)(-5650 2175);
WIRE 17 -1 (-5650 2175)(-5650 2225);
WIRE 17 -1 (-5650 2225)(-5650 2275);
WIRE 17 -1 (-5650 2275)(-5650 2325);
WIRE 17 -1 (-5650 2325)(-5650 2375);
WIRE 17 -1 (-5650 2375)(-5650 2425);
WIRE 17 -1 (-5650 2425)(-5650 2475);
WIRE 17 -1 (-5650 2475)(-5650 2525);
WIRE 17 -1 (-5650 2525)(-5650 2575);
WIRE 17 -1 (-5650 2575)(-5650 2625);
WIRE 17 -1 (-5650 2625)(-5650 2675);
WIRE 17 -1 (-5650 2675)(-5650 2725);
WIRE 17 -1 (-5650 2725)(-5650 2775);
WIRE 17 -1 (-5650 2775)(-5650 2825);
WIRE 17 -1 (-5650 2825)(-5650 2875);
WIRE 17 -1 (-5650 2875)(-5650 2925);
WIRE 17 -1 (-5650 2925)(-5650 2975);
WIRE 17 -1 (-5650 2975)(-5650 3025);
WIRE 17 -1 (-5650 3025)(-5650 3075);
WIRE 17 -1 (-5650 3075)(-5650 3125);
WIRE 17 -1 (-5650 3125)(-5650 3175);
WIRE 17 -1 (-5650 3175)(-5650 3225);
WIRE 17 -1 (-5650 3225)(-5650 3275);
WIRE 17 -1 (-5650 3275)(-5650 3325);
WIRE 17 -1 (-5650 3325)(-5650 3375);
WIRE 17 -1 (-5650 3375)(-5650 3425);
WIRE 17 -1 (-5650 3425)(-5650 3475);
WIRE 17 -1 (-5650 3475)(-5650 3525);
WIRE 17 -1 (-5650 3525)(-5650 3575);
WIRE 17 -1 (-5650 3575)(-5650 3625);
WIRE 17 -1 (-5650 3625)(-5650 3675);
WIRE 17 -1 (-5650 3675)(-5650 3725);
WIRE 17 -1 (-5650 3725)(-5650 3775);
WIRE 17 -1 (-5650 3775)(-5650 3825);
WIRE 17 -1 (-5650 3825)(-5650 3875);
WIRE 17 -1 (-5650 3875)(-5650 3925);
WIRE 17 -1 (-5650 3925)(-5650 3975);
WIRE 17 -1 (-5650 3975)(-5650 4025);
WIRE 17 -1 (-5650 4025)(-5650 4075);
WIRE 17 -1 (-5650 4075)(-5650 4125);
WIRE 17 -1 (-5650 4125)(-5650 4175);
WIRE 17 -1 (-5650 4175)(-5650 4225);
WIRE 17 -1 (-5650 4225)(-5650 4275);
WIRE 17 -1 (-5650 4275)(-5650 4325);
WIRE 17 -1 (-5650 4325)(-5650 4375);
WIRE 17 -1 (-5650 4375)(-5650 4425);
WIRE 17 -1 (-5650 4425)(-5650 4475);
WIRE 17 -1 (-5650 4475)(-5650 4525);
WIRE 17 -1 (-5650 4525)(-5650 4575);
WIRE 17 -1 (-5650 4575)(-5650 4625);
WIRE 17 -1 (-5650 4625)(-5650 4675);
WIRE 17 -1 (-5650 4675)(-5650 4725);
WIRE 17 -1 (-5650 4725)(-5650 4825);
WIRE 17 -1 (-5650 4825)(-6400 4825);
FORCEPROP 2 LAST SIG_NAME M_A_DQ<63:0>
J 0
(-6350 4835);
DISPLAY 0.617021 (-6350 4835);
PAINT ORANGE (-6350 4835);
WIRE 17 -1 (-5650 1125)(-5650 1175);
WIRE 17 -1 (-5650 1175)(-5650 1225);
WIRE 17 -1 (-5650 1225)(-5650 1275);
WIRE 17 -1 (-5650 1275)(-5650 1325);
WIRE 17 -1 (-5650 1325)(-5650 1375);
WIRE 17 -1 (-5650 1375)(-5650 1425);
WIRE 17 -1 (-5650 1425)(-5650 1475);
WIRE 17 -1 (-5650 1475)(-5650 1500);
WIRE 17 -1 (-5650 1500)(-6400 1500);
FORCEPROP 2 LAST SIG_NAME M_A_ECC<7:0>
J 0
(-6350 1510);
DISPLAY 0.617021 (-6350 1510);
PAINT ORANGE (-6350 1510);
WIRE 17 -1 (-5650 875)(-5650 925);
WIRE 17 -1 (-5650 925)(-5650 975);
WIRE 17 -1 (-5650 975)(-5650 1025);
WIRE 17 -1 (-5650 1025)(-5650 1050);
WIRE 17 -1 (-5650 1050)(-6400 1050);
FORCEPROP 2 LAST SIG_NAME M_A_CLK_DP<3:0>
J 0
(-6350 1060);
DISPLAY 0.617021 (-6350 1060);
PAINT ORANGE (-6350 1060);
WIRE 17 -1 (-5650 675)(-5650 725);
WIRE 17 -1 (-5650 725)(-5650 775);
WIRE 17 -1 (-5650 775)(-5650 825);
WIRE 17 -1 (-5650 825)(-5650 850);
WIRE 17 -1 (-5650 850)(-6400 850);
FORCEPROP 2 LAST SIG_NAME M_A_CLK_DN<3:0>
J 0
(-6350 860);
DISPLAY 0.617021 (-6350 860);
PAINT ORANGE (-6350 860);
WIRE 17 -1 (-2825 1475)(-2825 1525);
WIRE 17 -1 (-2825 1525)(-2825 1575);
WIRE 17 -1 (-2825 1575)(-2825 1625);
WIRE 17 -1 (-2825 1625)(-2825 1650);
WIRE 17 -1 (-2075 1650)(-2825 1650);
FORCEPROP 2 LAST SIG_NAME M_A_ODT<3:0>
J 0
(-2725 1660);
DISPLAY 0.617021 (-2725 1660);
PAINT ORANGE (-2725 1660);
WIRE 17 -1 (-2825 1975)(-2825 2025);
WIRE 17 -1 (-2825 2025)(-2825 2075);
WIRE 17 -1 (-2825 2075)(-2825 2125);
WIRE 17 -1 (-2825 2125)(-2825 2175);
WIRE 17 -1 (-2825 2175)(-2825 2225);
WIRE 17 -1 (-2825 2225)(-2825 2275);
WIRE 17 -1 (-2825 2275)(-2825 2325);
WIRE 17 -1 (-2825 2325)(-2825 2375);
WIRE 17 -1 (-2825 2375)(-2825 2425);
WIRE 17 -1 (-2825 2425)(-2825 2475);
WIRE 17 -1 (-2825 2475)(-2825 2525);
WIRE 17 -1 (-2825 2525)(-2825 2575);
WIRE 17 -1 (-2825 2575)(-2825 2625);
WIRE 17 -1 (-2825 2625)(-2825 2675);
WIRE 17 -1 (-2825 2675)(-2825 2725);
WIRE 17 -1 (-2825 2725)(-2825 2775);
WIRE 17 -1 (-2825 2775)(-2825 2825);
WIRE 17 -1 (-2825 2825)(-2825 2850);
WIRE 17 -1 (-2075 2850)(-2825 2850);
FORCEPROP 2 LAST SIG_NAME M_A_MA<17:0>
J 0
(-2725 2860);
DISPLAY 0.617021 (-2725 2860);
PAINT ORANGE (-2725 2860);
WIRE 17 -1 (-2825 1025)(-2825 1075);
WIRE 17 -1 (-2825 1075)(-2825 1125);
WIRE 17 -1 (-2825 1125)(-2825 1175);
WIRE 17 -1 (-2825 1175)(-2825 1225);
WIRE 17 -1 (-2825 1225)(-2825 1275);
WIRE 17 -1 (-2825 1275)(-2825 1325);
WIRE 17 -1 (-2825 1325)(-2825 1375);
WIRE 17 -1 (-2825 1375)(-2825 1400);
WIRE 17 -1 (-2075 1400)(-2825 1400);
FORCEPROP 2 LAST SIG_NAME M_A_CS_N<7:0>
J 0
(-2725 1410);
DISPLAY 0.617021 (-2725 1410);
PAINT ORANGE (-2725 1410);
WIRE 17 -1 (-2825 1725)(-2825 1775);
WIRE 17 -1 (-2825 1775)(-2825 1825);
WIRE 17 -1 (-2825 1825)(-2825 1875);
WIRE 17 -1 (-2825 1875)(-2825 1900);
WIRE 17 -1 (-2075 1900)(-2825 1900);
FORCEPROP 2 LAST SIG_NAME M_A_CKE<3:0>
J 0
(-2725 1910);
DISPLAY 0.617021 (-2725 1910);
PAINT ORANGE (-2725 1910);
WIRE 17 -1 (-2825 875)(-2825 925);
WIRE 17 -1 (-2825 925)(-2825 950);
WIRE 17 -1 (-2075 950)(-2825 950);
FORCEPROP 2 LAST SIG_NAME M_A_BG<1:0>
J 0
(-2725 960);
DISPLAY 0.617021 (-2725 960);
PAINT ORANGE (-2725 960);
WIRE 17 -1 (-2825 775)(-2825 825);
WIRE 17 -1 (-2825 825)(-2825 850);
WIRE 17 -1 (-2075 850)(-2825 850);
FORCEPROP 2 LAST SIG_NAME M_A_BA<1:0>
J 0
(-2725 860);
DISPLAY 0.617021 (-2725 860);
PAINT ORANGE (-2725 860);
WIRE 17 -1 (-2825 3875)(-2825 3925);
WIRE 17 -1 (-2825 3925)(-2825 3975);
WIRE 17 -1 (-2825 3975)(-2825 4025);
WIRE 17 -1 (-2825 4025)(-2825 4075);
WIRE 17 -1 (-2825 4075)(-2825 4125);
WIRE 17 -1 (-2825 4125)(-2825 4175);
WIRE 17 -1 (-2825 4175)(-2825 4225);
WIRE 17 -1 (-2825 4225)(-2825 4275);
WIRE 17 -1 (-2825 4275)(-2825 4325);
WIRE 17 -1 (-2825 4325)(-2825 4375);
WIRE 17 -1 (-2825 4375)(-2825 4425);
WIRE 17 -1 (-2825 4425)(-2825 4475);
WIRE 17 -1 (-2825 4475)(-2825 4525);
WIRE 17 -1 (-2825 4525)(-2825 4575);
WIRE 17 -1 (-2825 4575)(-2825 4625);
WIRE 17 -1 (-2825 4625)(-2825 4675);
WIRE 17 -1 (-2825 4675)(-2825 4725);
WIRE 17 -1 (-2825 4725)(-2825 4775);
WIRE 17 -1 (-2075 4775)(-2825 4775);
FORCEPROP 2 LAST SIG_NAME M_A_DQS_DP<17:0>
J 0
(-2725 4785);
DISPLAY 0.617021 (-2725 4785);
PAINT ORANGE (-2725 4785);
WIRE 17 -1 (-2825 2925)(-2825 2975);
WIRE 17 -1 (-2825 2975)(-2825 3025);
WIRE 17 -1 (-2825 3025)(-2825 3075);
WIRE 17 -1 (-2825 3075)(-2825 3125);
WIRE 17 -1 (-2825 3125)(-2825 3175);
WIRE 17 -1 (-2825 3175)(-2825 3225);
WIRE 17 -1 (-2825 3225)(-2825 3275);
WIRE 17 -1 (-2825 3275)(-2825 3325);
WIRE 17 -1 (-2825 3325)(-2825 3375);
WIRE 17 -1 (-2825 3375)(-2825 3425);
WIRE 17 -1 (-2825 3425)(-2825 3475);
WIRE 17 -1 (-2825 3475)(-2825 3525);
WIRE 17 -1 (-2825 3525)(-2825 3575);
WIRE 17 -1 (-2825 3575)(-2825 3625);
WIRE 17 -1 (-2825 3625)(-2825 3675);
WIRE 17 -1 (-2825 3675)(-2825 3725);
WIRE 17 -1 (-2825 3725)(-2825 3775);
WIRE 17 -1 (-2825 3775)(-2825 3800);
WIRE 17 -1 (-2075 3800)(-2825 3800);
FORCEPROP 2 LAST SIG_NAME M_A_DQS_DN<17:0>
J 0
(-2725 3810);
DISPLAY 0.617021 (-2725 3810);
PAINT ORANGE (-2725 3810);
WIRE 16 -1 (-3350 4700)(-2925 4700);
WIRE 16 -1 (-3350 4650)(-2925 4650);
WIRE 16 -1 (-3350 4600)(-2925 4600);
WIRE 16 -1 (-3350 4550)(-2925 4550);
WIRE 16 -1 (-3350 4500)(-2925 4500);
WIRE 16 -1 (-3350 4450)(-2925 4450);
WIRE 16 -1 (-3350 4400)(-2925 4400);
WIRE 16 -1 (-3350 4350)(-2925 4350);
WIRE 16 -1 (-3350 4300)(-2925 4300);
WIRE 16 -1 (-3350 4250)(-2925 4250);
WIRE 16 -1 (-3350 4200)(-2925 4200);
WIRE 16 -1 (-3350 4150)(-2925 4150);
WIRE 16 -1 (-3350 4100)(-2925 4100);
WIRE 16 -1 (-3350 3750)(-2925 3750);
WIRE 16 -1 (-3350 3700)(-2925 3700);
WIRE 16 -1 (-3350 3650)(-2925 3650);
WIRE 16 -1 (-3350 3600)(-2925 3600);
WIRE 16 -1 (-3350 3550)(-2925 3550);
WIRE 16 -1 (-3350 3500)(-2925 3500);
WIRE 16 -1 (-3350 3450)(-2925 3450);
WIRE 16 -1 (-3350 3400)(-2925 3400);
WIRE 16 -1 (-3350 3350)(-2925 3350);
WIRE 16 -1 (-3350 3300)(-2925 3300);
WIRE 16 -1 (-3350 3250)(-2925 3250);
WIRE 16 -1 (-3350 3200)(-2925 3200);
WIRE 16 -1 (-3350 3150)(-2925 3150);
WIRE 16 -1 (-3350 3100)(-2925 3100);
WIRE 16 -1 (-3350 3050)(-2925 3050);
WIRE 16 -1 (-3350 3000)(-2925 3000);
WIRE 16 -1 (-3350 2950)(-2925 2950);
WIRE 16 -1 (-3350 2900)(-2925 2900);
WIRE 16 -1 (-3350 4050)(-2925 4050);
WIRE 16 -1 (-3350 4000)(-2925 4000);
WIRE 16 -1 (-3350 3950)(-2925 3950);
WIRE 16 -1 (-3350 3900)(-2925 3900);
WIRE 16 -1 (-3350 3850)(-2925 3850);
WIRE 16 -1 (-3350 2800)(-2925 2800);
WIRE 16 -1 (-3350 2750)(-2925 2750);
WIRE 16 -1 (-3350 2700)(-2925 2700);
WIRE 16 -1 (-3350 2650)(-2925 2650);
WIRE 16 -1 (-3350 2600)(-2925 2600);
WIRE 16 -1 (-3350 2550)(-2925 2550);
WIRE 16 -1 (-3350 2500)(-2925 2500);
WIRE 16 -1 (-3350 2450)(-2925 2450);
WIRE 16 -1 (-3350 2400)(-2925 2400);
WIRE 16 -1 (-3350 2350)(-2925 2350);
WIRE 16 -1 (-3350 2300)(-2925 2300);
WIRE 16 -1 (-3350 2250)(-2925 2250);
WIRE 16 -1 (-3350 2200)(-2925 2200);
WIRE 16 -1 (-3350 2150)(-2925 2150);
WIRE 16 -1 (-3350 2100)(-2925 2100);
WIRE 16 -1 (-3350 2050)(-2925 2050);
WIRE 16 -1 (-2075 650)(-3350 650);
FORCEPROP 2 LAST SIG_NAME M_A_ACT_N
J 0
(-2725 660);
DISPLAY 0.617021 (-2725 660);
PAINT ORANGE (-2725 660);
WIRE 16 -1 (-2075 600)(-3350 600);
FORCEPROP 2 LAST SIG_NAME M_A_ALERT_N
J 0
(-2725 610);
DISPLAY 0.617021 (-2725 610);
PAINT ORANGE (-2725 610);
WIRE 16 -1 (-2075 550)(-3350 550);
FORCEPROP 2 LAST SIG_NAME M_A_PAR
J 0
(-2725 560);
DISPLAY 0.617021 (-2725 560);
PAINT ORANGE (-2725 560);
WIRE 16 -1 (-3350 800)(-2925 800);
WIRE 16 -1 (-3350 750)(-2925 750);
WIRE 16 -1 (-3350 900)(-2925 900);
WIRE 16 -1 (-3350 850)(-2925 850);
WIRE 16 -1 (-3350 1850)(-2925 1850);
WIRE 16 -1 (-3350 1800)(-2925 1800);
WIRE 16 -1 (-3350 1750)(-2925 1750);
WIRE 16 -1 (-3350 1700)(-2925 1700);
WIRE 16 -1 (-3350 1350)(-2925 1350);
WIRE 16 -1 (-3350 1300)(-2925 1300);
WIRE 16 -1 (-3350 1250)(-2925 1250);
WIRE 16 -1 (-3350 1200)(-2925 1200);
WIRE 16 -1 (-3350 1150)(-2925 1150);
WIRE 16 -1 (-3350 1100)(-2925 1100);
WIRE 16 -1 (-3350 1050)(-2925 1050);
WIRE 16 -1 (-3350 1000)(-2925 1000);
WIRE 16 -1 (-3350 2000)(-2925 2000);
WIRE 16 -1 (-3350 1950)(-2925 1950);
WIRE 16 -1 (-3350 1600)(-2925 1600);
WIRE 16 -1 (-3350 1550)(-2925 1550);
WIRE 16 -1 (-3350 1500)(-2925 1500);
WIRE 16 -1 (-3350 1450)(-2925 1450);
WIRE 16 -1 (-5050 4700)(-5550 4700);
WIRE 16 -1 (-5050 4650)(-5550 4650);
WIRE 16 -1 (-5050 4600)(-5550 4600);
WIRE 16 -1 (-5050 4550)(-5550 4550);
WIRE 16 -1 (-5050 4500)(-5550 4500);
WIRE 16 -1 (-5050 4450)(-5550 4450);
WIRE 16 -1 (-5050 4400)(-5550 4400);
WIRE 16 -1 (-5050 4350)(-5550 4350);
WIRE 16 -1 (-5050 4300)(-5550 4300);
WIRE 16 -1 (-5050 4250)(-5550 4250);
WIRE 16 -1 (-5050 4200)(-5550 4200);
WIRE 16 -1 (-5050 4150)(-5550 4150);
WIRE 16 -1 (-5050 4100)(-5550 4100);
WIRE 16 -1 (-5050 4050)(-5550 4050);
WIRE 16 -1 (-5050 4000)(-5550 4000);
WIRE 16 -1 (-5050 3950)(-5550 3950);
WIRE 16 -1 (-5050 3900)(-5550 3900);
WIRE 16 -1 (-5050 3850)(-5550 3850);
WIRE 16 -1 (-5050 3800)(-5550 3800);
WIRE 16 -1 (-5050 3750)(-5550 3750);
WIRE 16 -1 (-5050 3700)(-5550 3700);
WIRE 16 -1 (-5550 3650)(-5050 3650);
WIRE 16 -1 (-5550 3600)(-5050 3600);
WIRE 16 -1 (-5050 3550)(-5550 3550);
WIRE 16 -1 (-5550 3500)(-5050 3500);
WIRE 16 -1 (-5550 3450)(-5050 3450);
WIRE 16 -1 (-5050 3400)(-5550 3400);
WIRE 16 -1 (-5550 3350)(-5050 3350);
WIRE 16 -1 (-5550 3300)(-5050 3300);
WIRE 16 -1 (-5550 3250)(-5050 3250);
WIRE 16 -1 (-5550 3200)(-5050 3200);
WIRE 16 -1 (-5550 3150)(-5050 3150);
WIRE 16 -1 (-5550 3100)(-5050 3100);
WIRE 16 -1 (-5050 3050)(-5550 3050);
WIRE 16 -1 (-5550 3000)(-5050 3000);
WIRE 16 -1 (-5550 2950)(-5050 2950);
WIRE 16 -1 (-5550 2900)(-5050 2900);
WIRE 16 -1 (-5550 2850)(-5050 2850);
WIRE 16 -1 (-5550 2800)(-5050 2800);
WIRE 16 -1 (-5550 2750)(-5050 2750);
WIRE 16 -1 (-5050 2700)(-5550 2700);
WIRE 16 -1 (-5550 2650)(-5050 2650);
WIRE 16 -1 (-5550 2600)(-5050 2600);
WIRE 16 -1 (-5550 2550)(-5050 2550);
WIRE 16 -1 (-5550 2500)(-5050 2500);
WIRE 16 -1 (-5050 2450)(-5550 2450);
WIRE 16 -1 (-5550 2400)(-5050 2400);
WIRE 16 -1 (-5550 2350)(-5050 2350);
WIRE 16 -1 (-5050 2300)(-5550 2300);
WIRE 16 -1 (-5550 2250)(-5050 2250);
WIRE 16 -1 (-5550 2200)(-5050 2200);
WIRE 16 -1 (-5550 2150)(-5050 2150);
WIRE 16 -1 (-5550 2100)(-5050 2100);
WIRE 16 -1 (-5550 2050)(-5050 2050);
WIRE 16 -1 (-5050 800)(-5550 800);
WIRE 16 -1 (-5050 750)(-5550 750);
WIRE 16 -1 (-5050 700)(-5550 700);
WIRE 16 -1 (-5050 650)(-5550 650);
WIRE 16 -1 (-5050 1000)(-5550 1000);
WIRE 16 -1 (-5050 950)(-5550 950);
WIRE 16 -1 (-5050 900)(-5550 900);
WIRE 16 -1 (-5050 850)(-5550 850);
WIRE 16 -1 (-5550 2000)(-5050 2000);
WIRE 16 -1 (-5550 1950)(-5050 1950);
WIRE 16 -1 (-5550 1900)(-5050 1900);
WIRE 16 -1 (-5050 1850)(-5550 1850);
WIRE 16 -1 (-5550 1800)(-5050 1800);
WIRE 16 -1 (-5050 1700)(-5550 1700);
WIRE 16 -1 (-5550 1650)(-5050 1650);
WIRE 16 -1 (-5550 1600)(-5050 1600);
WIRE 16 -1 (-5550 1550)(-5050 1550);
WIRE 16 -1 (-5050 1450)(-5550 1450);
WIRE 16 -1 (-5050 1400)(-5550 1400);
WIRE 16 -1 (-5050 1350)(-5550 1350);
WIRE 16 -1 (-5050 1300)(-5550 1300);
WIRE 16 -1 (-5050 1250)(-5550 1250);
WIRE 16 -1 (-5050 1200)(-5550 1200);
WIRE 16 -1 (-5050 1150)(-5550 1150);
WIRE 16 -1 (-5050 1100)(-5550 1100);
WIRE 16 -1 (-5050 550)(-6400 550);
FORCEPROP 2 LAST SIG_NAME M_A_C<2>
J 0
(-6350 560);
DISPLAY 0.617021 (-6350 560);
PAINT ORANGE (-6350 560);
WIRE 16 -1 (-5550 1750)(-5050 1750);
FORCENOTE
ROOM=CPU0
(-7925 350) 0;
DISPLAY LEFT (-7925 350);
DISPLAY 1.382979 (-7925 350);
PAINT PURPLE (-7925 350);
FORCENOTE
BOM_COST=PROC_SOCKET
(-7925 225) 0;
DISPLAY LEFT (-7925 225);
DISPLAY 1.382979 (-7925 225);
PAINT PURPLE (-7925 225);
QUIT
